FILE_TYPE = MACRO_DRAWING;
SET COLOR_WIRE YELLOW;
SET COLOR_PROP MONO;
SET COLOR_DOT WHITE;
SET COLOR_ARC YELLOW;
SET COLOR_BODY GREEN;
SET COLOR_NOTE MONO;
SET PROP_DISPLAY VALUE;
SET PAGE_NUMBER P233;
FORCEADD CAP..1
(-8100 725);
FORCEPROP 1 LASTPIN (-8100 625) $PN 2
J 0
(-8090 605);
DISPLAY 0.617021 (-8090 605);
PAINT GREEN (-8090 605);
FORCEPROP 1 LAST MATERIAL X6S
J 0
(-8050 625);
DISPLAY 0.617021 (-8050 625);
PAINT SKYBLUE (-8050 625);
FORCEPROP 1 LAST TOLERANCE 20%
J 0
(-8050 675);
DISPLAY 0.617021 (-8050 675);
PAINT SKYBLUE (-8050 675);
FORCEPROP 1 LASTPIN (-8100 825) $PN 1
J 0
(-8090 805);
DISPLAY 0.617021 (-8090 805);
PAINT GREEN (-8090 805);
FORCEPROP 1 LAST PACK_TYPE 0603LF
J 0
(-8050 525);
DISPLAY 0.617021 (-8050 525);
PAINT SKYBLUE (-8050 525);
FORCEPROP 1 LAST VALUE 10UF
J 0
(-8050 775);
DISPLAY 0.617021 (-8050 775);
PAINT SKYBLUE (-8050 775);
FORCEPROP 1 LAST PART_NUMBER E15431-001
J 0
(-8050 575);
DISPLAY 0.617021 (-8050 575);
PAINT BLUE (-8050 575);
FORCEPROP 1 LAST LOCATION C7U4
J 0
(-8050 825);
DISPLAY 0.617021 (-8050 825);
PAINT AQUA (-8050 825);
FORCEPROP 2 LAST CDS_LIB mstr_discrete
J 0
(-8100 725);
PAINT ORANGE (-8100 725);
DISPLAY INVISIBLE (-8100 725);
FORCEPROP 1 LAST VOLTAGE 4V
J 0
(-8050 725);
PAINT SKYBLUE (-8050 725);
DISPLAY INVISIBLE (-8050 725);
FORCEPROP 2 LAST BOM_COST MEM_VRD_PVPP_AB
J 0
(-8050 875);
PAINT MONO (-8050 875);
DISPLAY INVISIBLE (-8050 875);
FORCEPROP 2 LAST CDS_SEC 1
J 0
(-8050 925);
PAINT MONO (-8050 925);
DISPLAY INVISIBLE (-8050 925);
FORCEPROP 2 LAST $SEC 1
J 0
(-8050 925);
PAINT MONO (-8050 925);
DISPLAY INVISIBLE (-8050 925);
FORCEPROP 2 LAST CDS_LOCATION C7U4
J 0
(-8050 825);
DISPLAY 0.617021 (-8050 825);
PAINT AQUA (-8050 825);
DISPLAY INVISIBLE (-8050 825);
FORCEPROP 1 LAST PATH I109
J 0
(-8050 875);
DISPLAY 0.978723 (-8050 875);
PAINT WHITE (-8050 875);
DISPLAY INVISIBLE (-8050 875);
FORCEPROP 2 LAST ROOM PVPP_KLM_VR
J 0
(-8050 875);
PAINT MONO (-8050 875);
DISPLAY INVISIBLE (-8050 875);
FORCEADD PVPP_GHJ..1
(-8100 1000);
FORCEPROP 3 LASTPIN (-8100 950) SIG_NAME PVPP_GHJ\g
J 0
(-8090 960);
DISPLAY 0.659574 (-8090 960);
PAINT MONO (-8090 960);
DISPLAY INVISIBLE (-8090 960);
FORCEPROP 1 LAST VOLTAGE 2.5V
J 0
(-8145 957);
DISPLAY 0.340426 (-8145 957);
PAINT SKYBLUE (-8145 957);
DISPLAY INVISIBLE (-8145 957);
FORCEPROP 1 LAST BODY_TYPE PLUMBING
J 0
(-8145 957);
DISPLAY 0.340426 (-8145 957);
PAINT GREEN (-8145 957);
DISPLAY INVISIBLE (-8145 957);
FORCEPROP 2 LAST CDS_LIB mstr_symbols
J 0
(-8100 1000);
PAINT ORANGE (-8100 1000);
DISPLAY INVISIBLE (-8100 1000);
FORCEPROP 2 LAST BOM_COST MEM_VRD_PVPP_AB
J 0
(-8025 1100);
PAINT MONO (-8025 1100);
DISPLAY INVISIBLE (-8025 1100);
FORCEPROP 1 LAST PATH I110
J 0
(-8050 1025);
DISPLAY 0.872340 (-8050 1025);
PAINT AQUA (-8050 1025);
DISPLAY INVISIBLE (-8050 1025);
FORCEPROP 2 LAST ROOM PVPP_KLM_VR
J 0
(-7850 1100);
PAINT ORANGE (-7850 1100);
DISPLAY INVISIBLE (-7850 1100);
FORCEPROP 1 LAST HDL_POWER PVPP_GHJ
J 1
(-8100 1050);
DISPLAY 0.872340 (-8100 1050);
PAINT GREEN (-8100 1050);
DISPLAY INVISIBLE (-8100 1050);
FORCEADD CAP..1
(-7850 725);
FORCEPROP 1 LASTPIN (-7850 625) $PN 2
J 0
(-7840 605);
DISPLAY 0.617021 (-7840 605);
PAINT GREEN (-7840 605);
FORCEPROP 1 LAST MATERIAL X6S
J 0
(-7800 625);
DISPLAY 0.617021 (-7800 625);
PAINT SKYBLUE (-7800 625);
FORCEPROP 1 LAST TOLERANCE 20%
J 0
(-7800 675);
DISPLAY 0.617021 (-7800 675);
PAINT SKYBLUE (-7800 675);
FORCEPROP 1 LASTPIN (-7850 825) $PN 1
J 0
(-7840 805);
DISPLAY 0.617021 (-7840 805);
PAINT GREEN (-7840 805);
FORCEPROP 1 LAST LOCATION C7U5
J 0
(-7800 825);
DISPLAY 0.617021 (-7800 825);
PAINT AQUA (-7800 825);
FORCEPROP 1 LAST VALUE 10UF
J 0
(-7800 775);
DISPLAY 0.617021 (-7800 775);
PAINT SKYBLUE (-7800 775);
FORCEPROP 1 LAST PACK_TYPE 0603LF
J 0
(-7800 525);
DISPLAY 0.617021 (-7800 525);
PAINT SKYBLUE (-7800 525);
FORCEPROP 1 LAST PART_NUMBER E15431-001
J 0
(-7800 575);
DISPLAY 0.617021 (-7800 575);
PAINT BLUE (-7800 575);
FORCEPROP 1 LAST VOLTAGE 4V
J 0
(-7800 725);
PAINT SKYBLUE (-7800 725);
DISPLAY INVISIBLE (-7800 725);
FORCEPROP 2 LAST CDS_LIB mstr_discrete
J 0
(-7850 725);
PAINT ORANGE (-7850 725);
DISPLAY INVISIBLE (-7850 725);
FORCEPROP 2 LAST ROOM PVPP_KLM_VR
J 0
(-7800 875);
PAINT MONO (-7800 875);
DISPLAY INVISIBLE (-7800 875);
FORCEPROP 1 LAST PATH I111
J 0
(-7800 875);
DISPLAY 0.978723 (-7800 875);
PAINT WHITE (-7800 875);
DISPLAY INVISIBLE (-7800 875);
FORCEPROP 2 LAST CDS_LOCATION C7U5
J 0
(-7800 825);
DISPLAY 0.617021 (-7800 825);
PAINT AQUA (-7800 825);
DISPLAY INVISIBLE (-7800 825);
FORCEPROP 2 LAST $SEC 1
J 0
(-7800 925);
PAINT MONO (-7800 925);
DISPLAY INVISIBLE (-7800 925);
FORCEPROP 2 LAST CDS_SEC 1
J 0
(-7800 925);
PAINT MONO (-7800 925);
DISPLAY INVISIBLE (-7800 925);
FORCEPROP 2 LAST BOM_COST MEM_VRD_PVPP_AB
J 0
(-7800 875);
PAINT MONO (-7800 875);
DISPLAY INVISIBLE (-7800 875);
FORCEADD CAP..1
(-7575 725);
FORCEPROP 1 LASTPIN (-7575 625) $PN 2
J 0
(-7565 605);
DISPLAY 0.617021 (-7565 605);
PAINT GREEN (-7565 605);
FORCEPROP 1 LAST MATERIAL X6S
J 0
(-7525 625);
DISPLAY 0.617021 (-7525 625);
PAINT SKYBLUE (-7525 625);
FORCEPROP 1 LAST TOLERANCE 20%
J 0
(-7525 675);
DISPLAY 0.617021 (-7525 675);
PAINT SKYBLUE (-7525 675);
FORCEPROP 1 LASTPIN (-7575 825) $PN 1
J 0
(-7565 805);
DISPLAY 0.617021 (-7565 805);
PAINT GREEN (-7565 805);
FORCEPROP 1 LAST PACK_TYPE 0603LF
J 0
(-7525 525);
DISPLAY 0.617021 (-7525 525);
PAINT SKYBLUE (-7525 525);
FORCEPROP 1 LAST VALUE 10UF
J 0
(-7525 775);
DISPLAY 0.617021 (-7525 775);
PAINT SKYBLUE (-7525 775);
FORCEPROP 1 LAST PART_NUMBER E15431-001
J 0
(-7525 575);
DISPLAY 0.617021 (-7525 575);
PAINT BLUE (-7525 575);
FORCEPROP 1 LAST LOCATION C7T2
J 0
(-7525 825);
DISPLAY 0.617021 (-7525 825);
PAINT AQUA (-7525 825);
FORCEPROP 1 LAST VOLTAGE 4V
J 0
(-7525 725);
PAINT SKYBLUE (-7525 725);
DISPLAY INVISIBLE (-7525 725);
FORCEPROP 2 LAST CDS_LIB mstr_discrete
J 0
(-7575 725);
PAINT ORANGE (-7575 725);
DISPLAY INVISIBLE (-7575 725);
FORCEPROP 2 LAST ROOM PVPP_KLM_VR
J 0
(-7525 875);
PAINT MONO (-7525 875);
DISPLAY INVISIBLE (-7525 875);
FORCEPROP 1 LAST PATH I112
J 0
(-7525 875);
DISPLAY 0.978723 (-7525 875);
PAINT WHITE (-7525 875);
DISPLAY INVISIBLE (-7525 875);
FORCEPROP 2 LAST CDS_LOCATION C7T2
J 0
(-7525 825);
DISPLAY 0.617021 (-7525 825);
PAINT AQUA (-7525 825);
DISPLAY INVISIBLE (-7525 825);
FORCEPROP 2 LAST $SEC 1
J 0
(-7525 925);
PAINT MONO (-7525 925);
DISPLAY INVISIBLE (-7525 925);
FORCEPROP 2 LAST CDS_SEC 1
J 0
(-7525 925);
PAINT MONO (-7525 925);
DISPLAY INVISIBLE (-7525 925);
FORCEPROP 2 LAST BOM_COST MEM_VRD_PVPP_AB
J 0
(-7525 875);
PAINT MONO (-7525 875);
DISPLAY INVISIBLE (-7525 875);
FORCEADD CAP..1
(-7325 700);
FORCEPROP 1 LASTPIN (-7325 600) $PN 2
J 0
(-7315 580);
DISPLAY 0.617021 (-7315 580);
PAINT GREEN (-7315 580);
FORCEPROP 1 LAST MATERIAL X6S
J 0
(-7275 600);
DISPLAY 0.617021 (-7275 600);
PAINT SKYBLUE (-7275 600);
FORCEPROP 1 LAST TOLERANCE 20%
J 0
(-7275 650);
DISPLAY 0.617021 (-7275 650);
PAINT SKYBLUE (-7275 650);
FORCEPROP 1 LASTPIN (-7325 800) $PN 1
J 0
(-7315 780);
DISPLAY 0.617021 (-7315 780);
PAINT GREEN (-7315 780);
FORCEPROP 1 LAST PACK_TYPE 0603LF
J 0
(-7275 500);
DISPLAY 0.617021 (-7275 500);
PAINT SKYBLUE (-7275 500);
FORCEPROP 1 LAST VALUE 10UF
J 0
(-7275 750);
DISPLAY 0.617021 (-7275 750);
PAINT SKYBLUE (-7275 750);
FORCEPROP 1 LAST PART_NUMBER E15431-001
J 0
(-7275 550);
DISPLAY 0.617021 (-7275 550);
PAINT BLUE (-7275 550);
FORCEPROP 1 LAST LOCATION C7T3
J 0
(-7275 800);
DISPLAY 0.617021 (-7275 800);
PAINT AQUA (-7275 800);
FORCEPROP 1 LAST VOLTAGE 4V
J 0
(-7275 700);
PAINT SKYBLUE (-7275 700);
DISPLAY INVISIBLE (-7275 700);
FORCEPROP 2 LAST CDS_LIB mstr_discrete
J 0
(-7325 700);
PAINT ORANGE (-7325 700);
DISPLAY INVISIBLE (-7325 700);
FORCEPROP 2 LAST ROOM PVPP_KLM_VR
J 0
(-7275 850);
PAINT MONO (-7275 850);
DISPLAY INVISIBLE (-7275 850);
FORCEPROP 1 LAST PATH I113
J 0
(-7275 850);
DISPLAY 0.978723 (-7275 850);
PAINT WHITE (-7275 850);
DISPLAY INVISIBLE (-7275 850);
FORCEPROP 2 LAST CDS_LOCATION C7T3
J 0
(-7275 800);
DISPLAY 0.617021 (-7275 800);
PAINT AQUA (-7275 800);
DISPLAY INVISIBLE (-7275 800);
FORCEPROP 2 LAST $SEC 1
J 0
(-7275 900);
PAINT MONO (-7275 900);
DISPLAY INVISIBLE (-7275 900);
FORCEPROP 2 LAST CDS_SEC 1
J 0
(-7275 900);
PAINT MONO (-7275 900);
DISPLAY INVISIBLE (-7275 900);
FORCEPROP 2 LAST BOM_COST MEM_VRD_PVPP_AB
J 0
(-7275 850);
PAINT MONO (-7275 850);
DISPLAY INVISIBLE (-7275 850);
FORCEADD CAP..1
(-7050 725);
FORCEPROP 1 LASTPIN (-7050 625) $PN 2
J 0
(-7040 605);
DISPLAY 0.617021 (-7040 605);
PAINT GREEN (-7040 605);
FORCEPROP 1 LAST MATERIAL X6S
J 0
(-7000 625);
DISPLAY 0.617021 (-7000 625);
PAINT SKYBLUE (-7000 625);
FORCEPROP 1 LAST TOLERANCE 20%
J 0
(-7000 675);
DISPLAY 0.617021 (-7000 675);
PAINT SKYBLUE (-7000 675);
FORCEPROP 1 LASTPIN (-7050 825) $PN 1
J 0
(-7040 805);
DISPLAY 0.617021 (-7040 805);
PAINT GREEN (-7040 805);
FORCEPROP 1 LAST PACK_TYPE 0603LF
J 0
(-7000 525);
DISPLAY 0.617021 (-7000 525);
PAINT SKYBLUE (-7000 525);
FORCEPROP 1 LAST VALUE 10UF
J 0
(-7000 775);
DISPLAY 0.617021 (-7000 775);
PAINT SKYBLUE (-7000 775);
FORCEPROP 1 LAST PART_NUMBER E15431-001
J 0
(-7000 575);
DISPLAY 0.617021 (-7000 575);
PAINT BLUE (-7000 575);
FORCEPROP 1 LAST LOCATION C7U6
J 0
(-7000 825);
DISPLAY 0.617021 (-7000 825);
PAINT AQUA (-7000 825);
FORCEPROP 1 LAST VOLTAGE 4V
J 0
(-7000 725);
PAINT SKYBLUE (-7000 725);
DISPLAY INVISIBLE (-7000 725);
FORCEPROP 2 LAST CDS_LIB mstr_discrete
J 0
(-7050 725);
PAINT ORANGE (-7050 725);
DISPLAY INVISIBLE (-7050 725);
FORCEPROP 2 LAST ROOM PVPP_KLM_VR
J 0
(-7000 875);
PAINT MONO (-7000 875);
DISPLAY INVISIBLE (-7000 875);
FORCEPROP 1 LAST PATH I115
J 0
(-7000 875);
DISPLAY 0.978723 (-7000 875);
PAINT WHITE (-7000 875);
DISPLAY INVISIBLE (-7000 875);
FORCEPROP 2 LAST CDS_LOCATION C7U6
J 0
(-7000 825);
DISPLAY 0.617021 (-7000 825);
PAINT AQUA (-7000 825);
DISPLAY INVISIBLE (-7000 825);
FORCEPROP 2 LAST $SEC 1
J 0
(-7000 925);
PAINT MONO (-7000 925);
DISPLAY INVISIBLE (-7000 925);
FORCEPROP 2 LAST CDS_SEC 1
J 0
(-7000 925);
PAINT MONO (-7000 925);
DISPLAY INVISIBLE (-7000 925);
FORCEPROP 2 LAST BOM_COST MEM_VRD_PVPP_AB
J 0
(-7000 875);
PAINT MONO (-7000 875);
DISPLAY INVISIBLE (-7000 875);
FORCEADD CAP..1
(-6750 725);
FORCEPROP 1 LASTPIN (-6750 625) $PN 2
J 0
(-6740 605);
DISPLAY 0.617021 (-6740 605);
PAINT GREEN (-6740 605);
FORCEPROP 1 LASTPIN (-6750 825) $PN 1
J 0
(-6740 805);
DISPLAY 0.617021 (-6740 805);
PAINT GREEN (-6740 805);
FORCEPROP 1 LAST MATERIAL X6S
J 0
(-6700 625);
DISPLAY 0.617021 (-6700 625);
PAINT SKYBLUE (-6700 625);
FORCEPROP 1 LAST PACK_TYPE 0603LF
J 0
(-6700 525);
DISPLAY 0.617021 (-6700 525);
PAINT SKYBLUE (-6700 525);
FORCEPROP 1 LAST TOLERANCE 20%
J 0
(-6700 675);
DISPLAY 0.617021 (-6700 675);
PAINT SKYBLUE (-6700 675);
FORCEPROP 1 LAST VALUE 10UF
J 0
(-6700 775);
DISPLAY 0.617021 (-6700 775);
PAINT SKYBLUE (-6700 775);
FORCEPROP 1 LAST PART_NUMBER E15431-001
J 0
(-6700 575);
DISPLAY 0.617021 (-6700 575);
PAINT BLUE (-6700 575);
FORCEPROP 1 LAST LOCATION C3F3
J 0
(-6700 825);
DISPLAY 0.617021 (-6700 825);
PAINT AQUA (-6700 825);
FORCEPROP 1 LAST VOLTAGE 4V
J 0
(-6700 725);
PAINT SKYBLUE (-6700 725);
DISPLAY INVISIBLE (-6700 725);
FORCEPROP 2 LAST CDS_LIB mstr_discrete
J 0
(-6750 725);
PAINT ORANGE (-6750 725);
DISPLAY INVISIBLE (-6750 725);
FORCEPROP 2 LAST CDS_LOCATION C3F3
J 0
(-6700 825);
DISPLAY 0.617021 (-6700 825);
PAINT AQUA (-6700 825);
DISPLAY INVISIBLE (-6700 825);
FORCEPROP 2 LAST ROOM PVPP_KLM_VR
J 0
(-6700 875);
PAINT MONO (-6700 875);
DISPLAY INVISIBLE (-6700 875);
FORCEPROP 2 LAST BOM_COST MEM_VRD_PVPP_AB
J 0
(-6700 875);
PAINT MONO (-6700 875);
DISPLAY INVISIBLE (-6700 875);
FORCEPROP 1 LAST PATH I116
J 0
(-6700 875);
DISPLAY 0.978723 (-6700 875);
PAINT WHITE (-6700 875);
DISPLAY INVISIBLE (-6700 875);
FORCEPROP 2 LAST $SEC 1
J 0
(-6700 925);
PAINT MONO (-6700 925);
DISPLAY INVISIBLE (-6700 925);
FORCEPROP 2 LAST CDS_SEC 1
J 0
(-6700 925);
PAINT MONO (-6700 925);
DISPLAY INVISIBLE (-6700 925);
FORCEADD CAP..1
(-6475 725);
FORCEPROP 1 LASTPIN (-6475 625) $PN 2
J 0
(-6465 605);
DISPLAY 0.617021 (-6465 605);
PAINT GREEN (-6465 605);
FORCEPROP 1 LASTPIN (-6475 825) $PN 1
J 0
(-6465 805);
DISPLAY 0.617021 (-6465 805);
PAINT GREEN (-6465 805);
FORCEPROP 1 LAST MATERIAL X6S
J 0
(-6425 625);
DISPLAY 0.617021 (-6425 625);
PAINT SKYBLUE (-6425 625);
FORCEPROP 1 LAST PACK_TYPE 0603LF
J 0
(-6425 525);
DISPLAY 0.617021 (-6425 525);
PAINT SKYBLUE (-6425 525);
FORCEPROP 1 LAST TOLERANCE 20%
J 0
(-6425 675);
DISPLAY 0.617021 (-6425 675);
PAINT SKYBLUE (-6425 675);
FORCEPROP 1 LAST VALUE 10UF
J 0
(-6425 775);
DISPLAY 0.617021 (-6425 775);
PAINT SKYBLUE (-6425 775);
FORCEPROP 1 LAST LOCATION C3F4
J 0
(-6425 825);
DISPLAY 0.617021 (-6425 825);
PAINT AQUA (-6425 825);
FORCEPROP 1 LAST PART_NUMBER E15431-001
J 0
(-6425 575);
DISPLAY 0.617021 (-6425 575);
PAINT BLUE (-6425 575);
FORCEPROP 1 LAST VOLTAGE 4V
J 0
(-6425 725);
PAINT SKYBLUE (-6425 725);
DISPLAY INVISIBLE (-6425 725);
FORCEPROP 2 LAST CDS_LIB mstr_discrete
J 0
(-6475 725);
PAINT MONO (-6475 725);
DISPLAY INVISIBLE (-6475 725);
FORCEPROP 2 LAST CDS_LOCATION C3F4
J 0
(-6425 825);
DISPLAY 0.617021 (-6425 825);
PAINT AQUA (-6425 825);
DISPLAY INVISIBLE (-6425 825);
FORCEPROP 2 LAST ROOM PVPP_KLM_VR
J 0
(-6425 875);
PAINT MONO (-6425 875);
DISPLAY INVISIBLE (-6425 875);
FORCEPROP 2 LAST BOM_COST MEM_VRD_PVPP_AB
J 0
(-6425 875);
PAINT MONO (-6425 875);
DISPLAY INVISIBLE (-6425 875);
FORCEPROP 1 LAST PATH I117
J 0
(-6425 875);
DISPLAY 0.978723 (-6425 875);
PAINT WHITE (-6425 875);
DISPLAY INVISIBLE (-6425 875);
FORCEPROP 2 LAST $SEC 1
J 0
(-6425 925);
PAINT MONO (-6425 925);
DISPLAY INVISIBLE (-6425 925);
FORCEPROP 2 LAST CDS_SEC 1
J 0
(-6425 925);
PAINT MONO (-6425 925);
DISPLAY INVISIBLE (-6425 925);
FORCEADD CAP..1
(-6175 725);
FORCEPROP 1 LASTPIN (-6175 825) $PN 1
J 0
(-6165 805);
DISPLAY 0.617021 (-6165 805);
PAINT GREEN (-6165 805);
FORCEPROP 1 LASTPIN (-6175 625) $PN 2
J 0
(-6165 605);
DISPLAY 0.617021 (-6165 605);
PAINT GREEN (-6165 605);
FORCEPROP 1 LAST MATERIAL X6S
J 0
(-6125 625);
DISPLAY 0.617021 (-6125 625);
PAINT SKYBLUE (-6125 625);
FORCEPROP 1 LAST PACK_TYPE 0603LF
J 0
(-6125 525);
DISPLAY 0.617021 (-6125 525);
PAINT SKYBLUE (-6125 525);
FORCEPROP 1 LAST TOLERANCE 20%
J 0
(-6125 675);
DISPLAY 0.617021 (-6125 675);
PAINT SKYBLUE (-6125 675);
FORCEPROP 1 LAST VALUE 10UF
J 0
(-6125 775);
DISPLAY 0.617021 (-6125 775);
PAINT SKYBLUE (-6125 775);
FORCEPROP 1 LAST LOCATION C3G3
J 0
(-6125 825);
DISPLAY 0.617021 (-6125 825);
PAINT AQUA (-6125 825);
FORCEPROP 1 LAST PART_NUMBER E15431-001
J 0
(-6125 575);
DISPLAY 0.617021 (-6125 575);
PAINT BLUE (-6125 575);
FORCEPROP 2 LAST CDS_LIB mstr_discrete
J 0
(-6175 725);
PAINT MONO (-6175 725);
DISPLAY INVISIBLE (-6175 725);
FORCEPROP 2 LAST ROOM PVPP_KLM_VR
J 0
(-6125 875);
PAINT MONO (-6125 875);
DISPLAY INVISIBLE (-6125 875);
FORCEPROP 1 LAST PATH I118
J 0
(-6125 875);
DISPLAY 0.978723 (-6125 875);
PAINT WHITE (-6125 875);
DISPLAY INVISIBLE (-6125 875);
FORCEPROP 2 LAST CDS_LOCATION C3G3
J 0
(-6125 825);
DISPLAY 0.617021 (-6125 825);
PAINT AQUA (-6125 825);
DISPLAY INVISIBLE (-6125 825);
FORCEPROP 2 LAST $SEC 1
J 0
(-6125 925);
PAINT MONO (-6125 925);
DISPLAY INVISIBLE (-6125 925);
FORCEPROP 2 LAST CDS_SEC 1
J 0
(-6125 925);
PAINT MONO (-6125 925);
DISPLAY INVISIBLE (-6125 925);
FORCEPROP 2 LAST BOM_COST MEM_VRD_PVPP_AB
J 0
(-6125 875);
PAINT MONO (-6125 875);
DISPLAY INVISIBLE (-6125 875);
FORCEPROP 1 LAST VOLTAGE 4V
J 0
(-6125 725);
PAINT SKYBLUE (-6125 725);
DISPLAY INVISIBLE (-6125 725);
FORCEADD CAP..1
(-5875 725);
FORCEPROP 1 LASTPIN (-5875 625) $PN 2
J 0
(-5865 605);
DISPLAY 0.617021 (-5865 605);
PAINT GREEN (-5865 605);
FORCEPROP 1 LAST MATERIAL X6S
J 0
(-5825 625);
DISPLAY 0.617021 (-5825 625);
PAINT SKYBLUE (-5825 625);
FORCEPROP 1 LAST PACK_TYPE 0603LF
J 0
(-5825 525);
DISPLAY 0.617021 (-5825 525);
PAINT SKYBLUE (-5825 525);
FORCEPROP 1 LAST TOLERANCE 20%
J 0
(-5825 675);
DISPLAY 0.617021 (-5825 675);
PAINT SKYBLUE (-5825 675);
FORCEPROP 1 LASTPIN (-5875 825) $PN 1
J 0
(-5865 805);
DISPLAY 0.617021 (-5865 805);
PAINT GREEN (-5865 805);
FORCEPROP 1 LAST VALUE 10UF
J 0
(-5825 775);
DISPLAY 0.617021 (-5825 775);
PAINT SKYBLUE (-5825 775);
FORCEPROP 1 LAST LOCATION C3G7
J 0
(-5825 825);
DISPLAY 0.617021 (-5825 825);
PAINT AQUA (-5825 825);
FORCEPROP 1 LAST PART_NUMBER E15431-001
J 0
(-5825 575);
DISPLAY 0.617021 (-5825 575);
PAINT BLUE (-5825 575);
FORCEPROP 2 LAST CDS_LIB mstr_discrete
J 0
(-5875 725);
PAINT MONO (-5875 725);
DISPLAY INVISIBLE (-5875 725);
FORCEPROP 1 LAST VOLTAGE 4V
J 0
(-5825 725);
PAINT SKYBLUE (-5825 725);
DISPLAY INVISIBLE (-5825 725);
FORCEPROP 2 LAST ROOM PVPP_KLM_VR
J 0
(-5825 875);
PAINT MONO (-5825 875);
DISPLAY INVISIBLE (-5825 875);
FORCEPROP 1 LAST PATH I132
J 0
(-5825 875);
DISPLAY 0.978723 (-5825 875);
PAINT WHITE (-5825 875);
DISPLAY INVISIBLE (-5825 875);
FORCEPROP 2 LAST CDS_LOCATION C3G7
J 0
(-5825 825);
DISPLAY 0.617021 (-5825 825);
PAINT AQUA (-5825 825);
DISPLAY INVISIBLE (-5825 825);
FORCEPROP 2 LAST $SEC 1
J 0
(-5825 925);
PAINT MONO (-5825 925);
DISPLAY INVISIBLE (-5825 925);
FORCEPROP 2 LAST CDS_SEC 1
J 0
(-5825 925);
PAINT MONO (-5825 925);
DISPLAY INVISIBLE (-5825 925);
FORCEPROP 2 LAST BOM_COST MEM_VRD_PVPP_AB
J 0
(-5825 875);
PAINT MONO (-5825 875);
DISPLAY INVISIBLE (-5825 875);
FORCEADD CAP..1
(-5600 700);
FORCEPROP 1 LAST PACK_TYPE 0603LF
J 0
(-5550 500);
DISPLAY 0.617021 (-5550 500);
PAINT SKYBLUE (-5550 500);
FORCEPROP 1 LASTPIN (-5600 600) $PN 2
J 0
(-5590 580);
DISPLAY 0.617021 (-5590 580);
PAINT GREEN (-5590 580);
FORCEPROP 1 LAST MATERIAL X6S
J 0
(-5550 600);
DISPLAY 0.617021 (-5550 600);
PAINT SKYBLUE (-5550 600);
FORCEPROP 1 LAST TOLERANCE 20%
J 0
(-5550 650);
DISPLAY 0.617021 (-5550 650);
PAINT SKYBLUE (-5550 650);
FORCEPROP 1 LAST VALUE 10UF
J 0
(-5550 750);
DISPLAY 0.617021 (-5550 750);
PAINT SKYBLUE (-5550 750);
FORCEPROP 1 LASTPIN (-5600 800) $PN 1
J 0
(-5590 780);
DISPLAY 0.617021 (-5590 780);
PAINT GREEN (-5590 780);
FORCEPROP 1 LAST LOCATION C3G4
J 0
(-5550 800);
DISPLAY 0.617021 (-5550 800);
PAINT AQUA (-5550 800);
FORCEPROP 1 LAST PART_NUMBER E15431-001
J 0
(-5550 550);
DISPLAY 0.617021 (-5550 550);
PAINT BLUE (-5550 550);
FORCEPROP 1 LAST VOLTAGE 4V
J 0
(-5550 700);
PAINT SKYBLUE (-5550 700);
DISPLAY INVISIBLE (-5550 700);
FORCEPROP 2 LAST CDS_LIB mstr_discrete
J 0
(-5600 700);
PAINT MONO (-5600 700);
DISPLAY INVISIBLE (-5600 700);
FORCEPROP 1 LAST PATH I133
J 0
(-5550 850);
DISPLAY 0.978723 (-5550 850);
PAINT WHITE (-5550 850);
DISPLAY INVISIBLE (-5550 850);
FORCEPROP 2 LAST CDS_LOCATION C3G4
J 0
(-5550 800);
DISPLAY 0.617021 (-5550 800);
PAINT AQUA (-5550 800);
DISPLAY INVISIBLE (-5550 800);
FORCEPROP 2 LAST BOM_COST MEM_VRD_PVPP_AB
J 0
(-5550 850);
PAINT MONO (-5550 850);
DISPLAY INVISIBLE (-5550 850);
FORCEPROP 2 LAST ROOM PVPP_KLM_VR
J 0
(-5550 850);
PAINT MONO (-5550 850);
DISPLAY INVISIBLE (-5550 850);
FORCEPROP 2 LAST $SEC 1
J 0
(-5550 900);
PAINT MONO (-5550 900);
DISPLAY INVISIBLE (-5550 900);
FORCEPROP 2 LAST CDS_SEC 1
J 0
(-5550 900);
PAINT MONO (-5550 900);
DISPLAY INVISIBLE (-5550 900);
FORCEADD GND..1
(-5150 400);
FORCEPROP 3 LASTPIN (-5150 450) SIG_NAME GND\g
J 0
(-5140 460);
DISPLAY 0.659574 (-5140 460);
PAINT MONO (-5140 460);
DISPLAY INVISIBLE (-5140 460);
FORCEPROP 2 LAST ROOM PVPP_KLM_VR
J 0
(-5700 475);
PAINT ORANGE (-5700 475);
DISPLAY INVISIBLE (-5700 475);
FORCEPROP 1 LAST BODY_TYPE PLUMBING
J 0
(-5195 357);
DISPLAY 0.340426 (-5195 357);
PAINT GREEN (-5195 357);
DISPLAY INVISIBLE (-5195 357);
FORCEPROP 2 LAST CDS_LIB mstr_symbols
J 0
(-5150 400);
PAINT MONO (-5150 400);
DISPLAY INVISIBLE (-5150 400);
FORCEPROP 1 LAST VOLTAGE 0
J 0
(-5150 400);
PAINT SKYBLUE (-5150 400);
DISPLAY INVISIBLE (-5150 400);
FORCEPROP 2 LAST BOM_COST MEM_VRD_PVPP_AB
J 0
(-5475 475);
PAINT MONO (-5475 475);
DISPLAY INVISIBLE (-5475 475);
FORCEPROP 1 LAST HDL_POWER GND
J 0
(-5150 550);
DISPLAY 0.893617 (-5150 550);
PAINT GREEN (-5150 550);
DISPLAY INVISIBLE (-5150 550);
FORCEPROP 1 LAST PATH I134
J 0
(-5075 400);
DISPLAY 0.872340 (-5075 400);
PAINT AQUA (-5075 400);
DISPLAY INVISIBLE (-5075 400);
FORCEPROP 1 LAST SIZE 1B
J 0
(-5075 350);
DISPLAY 0.893617 (-5075 350);
PAINT GREEN (-5075 350);
DISPLAY INVISIBLE (-5075 350);
FORCEADD CAP..1
(-5325 700);
FORCEPROP 1 LASTPIN (-5325 600) $PN 2
J 0
(-5315 580);
DISPLAY 0.617021 (-5315 580);
PAINT GREEN (-5315 580);
FORCEPROP 1 LAST TOLERANCE 20%
J 0
(-5275 650);
DISPLAY 0.617021 (-5275 650);
PAINT SKYBLUE (-5275 650);
FORCEPROP 1 LAST MATERIAL X6S
J 0
(-5275 600);
DISPLAY 0.617021 (-5275 600);
PAINT SKYBLUE (-5275 600);
FORCEPROP 1 LAST VALUE 10UF
J 0
(-5275 750);
DISPLAY 0.617021 (-5275 750);
PAINT SKYBLUE (-5275 750);
FORCEPROP 1 LASTPIN (-5325 800) $PN 1
J 0
(-5315 780);
DISPLAY 0.617021 (-5315 780);
PAINT GREEN (-5315 780);
FORCEPROP 1 LAST LOCATION C3G8
J 0
(-5275 800);
DISPLAY 0.617021 (-5275 800);
PAINT AQUA (-5275 800);
FORCEPROP 1 LAST PACK_TYPE 0603LF
J 0
(-5275 500);
DISPLAY 0.617021 (-5275 500);
PAINT SKYBLUE (-5275 500);
FORCEPROP 1 LAST PART_NUMBER E15431-001
J 0
(-5275 550);
DISPLAY 0.617021 (-5275 550);
PAINT BLUE (-5275 550);
FORCEPROP 1 LAST VOLTAGE 4V
J 0
(-5275 700);
PAINT SKYBLUE (-5275 700);
DISPLAY INVISIBLE (-5275 700);
FORCEPROP 2 LAST CDS_LIB mstr_discrete
J 0
(-5325 700);
PAINT MONO (-5325 700);
DISPLAY INVISIBLE (-5325 700);
FORCEPROP 2 LAST BOM_COST MEM_VRD_PVPP_AB
J 0
(-5275 850);
PAINT MONO (-5275 850);
DISPLAY INVISIBLE (-5275 850);
FORCEPROP 2 LAST CDS_LOCATION C3G8
J 0
(-5275 800);
DISPLAY 0.617021 (-5275 800);
PAINT AQUA (-5275 800);
DISPLAY INVISIBLE (-5275 800);
FORCEPROP 1 LAST PATH I135
J 0
(-5275 850);
DISPLAY 0.978723 (-5275 850);
PAINT WHITE (-5275 850);
DISPLAY INVISIBLE (-5275 850);
FORCEPROP 2 LAST ROOM PVPP_KLM_VR
J 0
(-5275 850);
PAINT MONO (-5275 850);
DISPLAY INVISIBLE (-5275 850);
FORCEPROP 2 LAST $SEC 1
J 0
(-5275 900);
PAINT MONO (-5275 900);
DISPLAY INVISIBLE (-5275 900);
FORCEPROP 2 LAST CDS_SEC 1
J 0
(-5275 900);
PAINT MONO (-5275 900);
DISPLAY INVISIBLE (-5275 900);
FORCEADD CAP..1
(-5075 725);
FORCEPROP 1 LAST TOLERANCE 20%
J 0
(-5025 675);
DISPLAY 0.617021 (-5025 675);
PAINT SKYBLUE (-5025 675);
FORCEPROP 1 LAST MATERIAL X6S
J 0
(-5025 625);
DISPLAY 0.617021 (-5025 625);
PAINT SKYBLUE (-5025 625);
FORCEPROP 1 LASTPIN (-5075 625) $PN 2
J 0
(-5065 605);
DISPLAY 0.617021 (-5065 605);
PAINT GREEN (-5065 605);
FORCEPROP 1 LAST VALUE 10UF
J 0
(-5025 775);
DISPLAY 0.617021 (-5025 775);
PAINT SKYBLUE (-5025 775);
FORCEPROP 1 LAST LOCATION C7U3
J 0
(-5025 825);
DISPLAY 0.617021 (-5025 825);
PAINT AQUA (-5025 825);
FORCEPROP 1 LASTPIN (-5075 825) $PN 1
J 0
(-5065 805);
DISPLAY 0.617021 (-5065 805);
PAINT GREEN (-5065 805);
FORCEPROP 1 LAST PART_NUMBER E15431-001
J 0
(-5025 575);
DISPLAY 0.617021 (-5025 575);
PAINT BLUE (-5025 575);
FORCEPROP 1 LAST PACK_TYPE 0603LF
J 0
(-5025 525);
DISPLAY 0.617021 (-5025 525);
PAINT SKYBLUE (-5025 525);
FORCEPROP 2 LAST CDS_LIB mstr_discrete
J 0
(-5075 725);
PAINT MONO (-5075 725);
DISPLAY INVISIBLE (-5075 725);
FORCEPROP 1 LAST VOLTAGE 4V
J 0
(-5025 725);
PAINT SKYBLUE (-5025 725);
DISPLAY INVISIBLE (-5025 725);
FORCEPROP 2 LAST CDS_LOCATION C7U3
J 0
(-5025 825);
DISPLAY 0.617021 (-5025 825);
PAINT AQUA (-5025 825);
DISPLAY INVISIBLE (-5025 825);
FORCEPROP 1 LAST PATH I136
J 0
(-5025 875);
DISPLAY 0.978723 (-5025 875);
PAINT WHITE (-5025 875);
DISPLAY INVISIBLE (-5025 875);
FORCEPROP 2 LAST ROOM PVPP_KLM_VR
J 0
(-5025 875);
PAINT MONO (-5025 875);
DISPLAY INVISIBLE (-5025 875);
FORCEPROP 2 LAST SEC_TYPE 0603LF
J 0
(-5005 945);
DISPLAY 1.021277 (-5005 945);
PAINT ORANGE (-5005 945);
DISPLAY INVISIBLE (-5005 945);
FORCEPROP 2 LAST BOM_COST MEM_VRD_PVPP_AB
J 0
(-5025 875);
PAINT MONO (-5025 875);
DISPLAY INVISIBLE (-5025 875);
FORCEPROP 2 LAST SEC 1
J 0
(-5005 945);
DISPLAY 0.680851 (-5005 945);
PAINT MONO (-5005 945);
DISPLAY INVISIBLE (-5005 945);
FORCEADD GND..1
(-1400 450);
FORCEPROP 3 LASTPIN (-1400 500) SIG_NAME GND\g
J 0
(-1390 510);
DISPLAY 0.659574 (-1390 510);
PAINT MONO (-1390 510);
DISPLAY INVISIBLE (-1390 510);
FORCEPROP 2 LAST BOM_COST PVPP_KLM_VR
J 0
(-2250 525);
DISPLAY 1.042553 (-2250 525);
PAINT WHITE (-2250 525);
DISPLAY INVISIBLE (-2250 525);
FORCEPROP 2 LAST ROOM PVPP_KLM_VR
J 0
(-1975 525);
DISPLAY 1.042553 (-1975 525);
PAINT GREEN (-1975 525);
DISPLAY INVISIBLE (-1975 525);
FORCEPROP 1 LAST PATH I156
J 0
(-1325 450);
DISPLAY 0.872340 (-1325 450);
PAINT AQUA (-1325 450);
DISPLAY INVISIBLE (-1325 450);
FORCEPROP 1 LAST BODY_TYPE PLUMBING
J 0
(-1445 407);
DISPLAY 0.340426 (-1445 407);
PAINT GREEN (-1445 407);
DISPLAY INVISIBLE (-1445 407);
FORCEPROP 2 LAST CDS_LIB mstr_symbols
J 0
(-1400 450);
PAINT MONO (-1400 450);
DISPLAY INVISIBLE (-1400 450);
FORCEPROP 1 LAST SIZE 1B
J 0
(-1325 400);
DISPLAY 0.872340 (-1325 400);
PAINT AQUA (-1325 400);
DISPLAY INVISIBLE (-1325 400);
FORCEPROP 1 LAST VOLTAGE 0
J 0
(-1400 450);
PAINT SKYBLUE (-1400 450);
DISPLAY INVISIBLE (-1400 450);
FORCEPROP 1 LAST HDL_POWER GND
J 0
(-1400 600);
DISPLAY 0.872340 (-1400 600);
PAINT GREEN (-1400 600);
DISPLAY INVISIBLE (-1400 600);
FORCEADD RES..1
(-1100 550);
FORCEPROP 1 LAST WATTAGE 1/16W
J 2
(-1100 400);
DISPLAY 0.617021 (-1100 400);
PAINT SKYBLUE (-1100 400);
FORCEPROP 1 LAST PACK_TYPE 0402
J 0
(-1175 350);
DISPLAY 0.617021 (-1175 350);
PAINT SKYBLUE (-1175 350);
FORCEPROP 1 LAST TOLERANCE 5%
J 0
(-1100 450);
DISPLAY 0.617021 (-1100 450);
PAINT SKYBLUE (-1100 450);
FORCEPROP 1 LAST VALUE 0.0
J 2
(-1125 450);
DISPLAY 0.617021 (-1125 450);
PAINT SKYBLUE (-1125 450);
FORCEPROP 1 LASTPIN (-1200 550) $PN 1
J 0
(-1188 562);
DISPLAY 0.617021 (-1188 562);
PAINT WHITE (-1188 562);
FORCEPROP 1 LASTPIN (-1000 550) $PN 2
J 0
(-1038 562);
DISPLAY 0.617021 (-1038 562);
PAINT WHITE (-1038 562);
FORCEPROP 1 LAST MATERIAL CHIP
J 0
(-1100 400);
DISPLAY 0.617021 (-1100 400);
PAINT SKYBLUE (-1100 400);
FORCEPROP 1 LAST PART_NUMBER G21497-005
J 0
(-1225 500);
DISPLAY 0.617021 (-1225 500);
PAINT BLUE (-1225 500);
FORCEPROP 1 LAST LOCATION R4G25
J 0
(-1150 600);
DISPLAY 0.617021 (-1150 600);
PAINT AQUA (-1150 600);
FORCEPROP 2 LAST CDS_LIB mstr_discrete
J 0
(-1100 550);
PAINT MONO (-1100 550);
DISPLAY INVISIBLE (-1100 550);
FORCEPROP 1 LAST PATH I157
J 0
(-1150 700);
DISPLAY 0.978723 (-1150 700);
PAINT WHITE (-1150 700);
DISPLAY INVISIBLE (-1150 700);
FORCEPROP 2 LAST ROOM PVPP_KLM_VR
J 0
(-1150 625);
PAINT GREEN (-1150 625);
DISPLAY INVISIBLE (-1150 625);
FORCEPROP 2 LAST CDS_SEC 1
J 0
(-1140 735);
PAINT MONO (-1140 735);
DISPLAY INVISIBLE (-1140 735);
FORCEPROP 2 LAST $SEC 1
J 0
(-1135 755);
PAINT MONO (-1135 755);
DISPLAY INVISIBLE (-1135 755);
FORCEADD AGND_SCSI..1
(-850 450);
FORCEPROP 3 LASTPIN (-850 500) SIG_NAME AGND_PVPP_GHJ\g
J 0
(-840 510);
DISPLAY 0.659574 (-840 510);
PAINT MONO (-840 510);
DISPLAY INVISIBLE (-840 510);
FORCEPROP 1 LAST HDL_POWER AGND_PVPP_GHJ
J 1
(-775 375);
DISPLAY 0.617021 (-775 375);
PAINT GREEN (-775 375);
FORCEPROP 2 LAST CDS_LIB mstr_symbols
J 0
(-850 450);
PAINT ORANGE (-850 450);
DISPLAY INVISIBLE (-850 450);
FORCEPROP 1 LAST VOLTAGE 0.0V
J 0
(-895 407);
DISPLAY 0.340426 (-895 407);
PAINT SKYBLUE (-895 407);
DISPLAY INVISIBLE (-895 407);
FORCEPROP 1 LAST BODY_TYPE PLUMBING
J 0
(-895 407);
DISPLAY 0.340426 (-895 407);
PAINT GREEN (-895 407);
DISPLAY INVISIBLE (-895 407);
FORCEPROP 2 LAST ROOM PVPP_KLM_VR
J 0
(-1000 400);
DISPLAY 1.042553 (-1000 400);
PAINT GREEN (-1000 400);
DISPLAY INVISIBLE (-1000 400);
FORCEPROP 1 LAST PATH I158
J 0
(-775 450);
DISPLAY 0.872340 (-775 450);
PAINT AQUA (-775 450);
DISPLAY INVISIBLE (-775 450);
FORCEPROP 2 LAST BOM_COST PVPP_KLM_VR
J 0
(-1000 400);
DISPLAY 1.042553 (-1000 400);
PAINT WHITE (-1000 400);
DISPLAY INVISIBLE (-1000 400);
FORCEADD PVPP_GHJ..1
(-725 3825);
FORCEPROP 3 LASTPIN (-725 3775) SIG_NAME PVPP_GHJ\g
J 0
(-715 3785);
DISPLAY 0.659574 (-715 3785);
PAINT MONO (-715 3785);
DISPLAY INVISIBLE (-715 3785);
FORCEPROP 1 LAST BODY_TYPE PLUMBING
J 0
(-770 3782);
DISPLAY 0.340426 (-770 3782);
PAINT GREEN (-770 3782);
DISPLAY INVISIBLE (-770 3782);
FORCEPROP 1 LAST VOLTAGE 2.5V
J 0
(-770 3782);
DISPLAY 0.340426 (-770 3782);
PAINT SKYBLUE (-770 3782);
DISPLAY INVISIBLE (-770 3782);
FORCEPROP 2 LAST CDS_LIB mstr_symbols
J 0
(-725 3825);
PAINT ORANGE (-725 3825);
DISPLAY INVISIBLE (-725 3825);
FORCEPROP 2 LAST BOM_COST PVPP_KLM_VR
J 0
(-650 3925);
PAINT MONO (-650 3925);
DISPLAY INVISIBLE (-650 3925);
FORCEPROP 1 LAST PATH I174
J 0
(-675 3850);
DISPLAY 0.872340 (-675 3850);
PAINT AQUA (-675 3850);
DISPLAY INVISIBLE (-675 3850);
FORCEPROP 1 LAST HDL_POWER PVPP_GHJ
J 1
(-725 3875);
DISPLAY 0.872340 (-725 3875);
PAINT GREEN (-725 3875);
DISPLAY INVISIBLE (-725 3875);
FORCEPROP 2 LAST ROOM PVPP_KLM_VR
J 0
(-475 3925);
PAINT ORANGE (-475 3925);
DISPLAY INVISIBLE (-475 3925);
FORCEADD GND..1
(-7175 1725);
FORCEPROP 3 LASTPIN (-7175 1775) SIG_NAME GND\g
J 0
(-7165 1785);
DISPLAY 0.659574 (-7165 1785);
PAINT MONO (-7165 1785);
DISPLAY INVISIBLE (-7165 1785);
FORCEPROP 2 LAST BOM SYSB_CPLD
J 0
(-7925 1900);
DISPLAY 1.042553 (-7925 1900);
PAINT ORANGE (-7925 1900);
DISPLAY INVISIBLE (-7925 1900);
FORCEPROP 2 LAST BOM_COST PVPP_KLM_VR
J 0
(-7925 1850);
DISPLAY 1.042553 (-7925 1850);
PAINT WHITE (-7925 1850);
DISPLAY INVISIBLE (-7925 1850);
FORCEPROP 2 LAST ROOM PVPP_KLM_VR
J 0
(-7925 1800);
DISPLAY 1.042553 (-7925 1800);
PAINT GREEN (-7925 1800);
DISPLAY INVISIBLE (-7925 1800);
FORCEPROP 1 LAST VOLTAGE 0
J 0
(-7175 1725);
PAINT SKYBLUE (-7175 1725);
DISPLAY INVISIBLE (-7175 1725);
FORCEPROP 2 LAST CDS_LIB mstr_symbols
J 0
(-7175 1725);
PAINT MONO (-7175 1725);
DISPLAY INVISIBLE (-7175 1725);
FORCEPROP 1 LAST BODY_TYPE PLUMBING
J 0
(-7220 1682);
DISPLAY 0.340426 (-7220 1682);
PAINT GREEN (-7220 1682);
DISPLAY INVISIBLE (-7220 1682);
FORCEPROP 1 LAST HDL_POWER GND
J 0
(-7175 1875);
DISPLAY 0.680851 (-7175 1875);
PAINT GREEN (-7175 1875);
DISPLAY INVISIBLE (-7175 1875);
FORCEPROP 1 LAST PATH I180
J 0
(-7100 1725);
DISPLAY 0.872340 (-7100 1725);
PAINT AQUA (-7100 1725);
DISPLAY INVISIBLE (-7100 1725);
FORCEPROP 1 LAST SIZE 1B
J 0
(-7100 1675);
DISPLAY 0.680851 (-7100 1675);
PAINT ORANGE (-7100 1675);
DISPLAY INVISIBLE (-7100 1675);
FORCEADD OFFPAGE..1
(-7575 2675);
FORCEPROP 2 LAST $XR0 191 
J 0
(-7827 2675);
DISPLAY 0.638298 (-7827 2675);
PAINT MONO (-7827 2675);
FORCEPROP 2 LAST $XR1 234 
J 0
(-7947 2675);
DISPLAY 0.638298 (-7947 2675);
PAINT MONO (-7947 2675);
FORCEPROP 2 LAST BOM_COST PVPP_KLM_VR
J 0
(-8400 2750);
DISPLAY 1.042553 (-8400 2750);
PAINT WHITE (-8400 2750);
DISPLAY INVISIBLE (-8400 2750);
FORCEPROP 2 LAST PATH I181
J 0
(-7825 2725);
DISPLAY 1.021277 (-7825 2725);
PAINT ORANGE (-7825 2725);
DISPLAY INVISIBLE (-7825 2725);
FORCEPROP 2 LAST ROOM PVPP_KLM_VR
J 0
(-8125 2750);
DISPLAY 1.042553 (-8125 2750);
PAINT GREEN (-8125 2750);
DISPLAY INVISIBLE (-8125 2750);
FORCEPROP 1 LAST OFFPAGE TRUE
J 0
(-7250 2550);
PAINT GREEN (-7250 2550);
DISPLAY INVISIBLE (-7250 2550);
FORCEPROP 2 LAST CDS_LIB mstr_standard
J 0
(-7575 2675);
PAINT MONO (-7575 2675);
DISPLAY INVISIBLE (-7575 2675);
FORCEPROP 1 LAST COMMENT_BODY TRUE
J 0
(-7450 2575);
DISPLAY 0.872340 (-7450 2575);
PAINT PEACH (-7450 2575);
DISPLAY INVISIBLE (-7450 2575);
FORCEPROP 0 LAST TOLERANCE 1%
J 0
(-7525 2750);
PAINT SKYBLUE (-7525 2750);
DISPLAY INVISIBLE (-7525 2750);
FORCEADD RES..2
(-7175 2125);
FORCEPROP 1 LAST PACK_TYPE 0402
J 0
(-7135 1950);
DISPLAY 0.617021 (-7135 1950);
PAINT SKYBLUE (-7135 1950);
FORCEPROP 1 LAST PART_NUMBER G21796-016
J 0
(-7160 2000);
DISPLAY 0.617021 (-7160 2000);
PAINT BLUE (-7160 2000);
FORCEPROP 1 LASTPIN (-7175 2025) $PN 2
J 0
(-7170 2035);
DISPLAY 0.617021 (-7170 2035);
PAINT WHITE (-7170 2035);
FORCEPROP 1 LASTPIN (-7175 2225) $PN 1
J 0
(-7170 2187);
DISPLAY 0.617021 (-7170 2187);
PAINT WHITE (-7170 2187);
FORCEPROP 1 LAST WATTAGE 1/16W
J 0
(-7135 2100);
DISPLAY 0.617021 (-7135 2100);
PAINT SKYBLUE (-7135 2100);
FORCEPROP 1 LAST MATERIAL CHIP
J 0
(-7135 2050);
DISPLAY 0.617021 (-7135 2050);
PAINT SKYBLUE (-7135 2050);
FORCEPROP 1 LAST TOLERANCE 1%
J 0
(-7130 2150);
DISPLAY 0.617021 (-7130 2150);
PAINT SKYBLUE (-7130 2150);
FORCEPROP 1 LAST VALUE 10.0K
J 0
(-7130 2200);
DISPLAY 0.617021 (-7130 2200);
PAINT SKYBLUE (-7130 2200);
FORCEPROP 1 LAST LOCATION R4G5
J 0
(-7130 2250);
DISPLAY 0.617021 (-7130 2250);
PAINT AQUA (-7130 2250);
FORCEPROP 2 LAST CDS_LIB mstr_discrete
J 0
(-7175 2125);
PAINT MONO (-7175 2125);
DISPLAY INVISIBLE (-7175 2125);
FORCEPROP 2 LAST ROOM PVPP_KLM_VR
J 0
(-7125 2350);
DISPLAY 1.042553 (-7125 2350);
PAINT GREEN (-7125 2350);
DISPLAY INVISIBLE (-7125 2350);
FORCEPROP 1 LAST PATH I182
J 0
(-7125 2300);
DISPLAY 0.978723 (-7125 2300);
PAINT WHITE (-7125 2300);
DISPLAY INVISIBLE (-7125 2300);
FORCEPROP 2 LAST CDS_LOCATION R4G5
J 0
(-7130 2250);
DISPLAY 0.617021 (-7130 2250);
PAINT AQUA (-7130 2250);
DISPLAY INVISIBLE (-7130 2250);
FORCEPROP 2 LAST $SEC 1
J 0
(-7125 2350);
DISPLAY 0.680851 (-7125 2350);
PAINT MONO (-7125 2350);
DISPLAY INVISIBLE (-7125 2350);
FORCEPROP 2 LAST CDS_SEC 1
J 0
(-7125 2350);
DISPLAY 1.042553 (-7125 2350);
PAINT ORANGE (-7125 2350);
DISPLAY INVISIBLE (-7125 2350);
FORCEPROP 0 LAST BOM SYSB_CPLD
J 0
(-7125 2450);
DISPLAY 1.042553 (-7125 2450);
PAINT ORANGE (-7125 2450);
DISPLAY INVISIBLE (-7125 2450);
FORCEPROP 2 LAST BOM_COST PVPP_KLM_VR
J 0
(-7125 2350);
DISPLAY 1.042553 (-7125 2350);
PAINT WHITE (-7125 2350);
DISPLAY INVISIBLE (-7125 2350);
FORCEADD CAP..1
R 2
(-6500 2200);
FORCEPROP 1 LAST PACK_TYPE 0402LF
J 2
(-6550 2000);
DISPLAY 0.617021 (-6550 2000);
PAINT SKYBLUE (-6550 2000);
FORCEPROP 1 LAST VALUE 1000PF
J 2
(-6550 2250);
DISPLAY 0.617021 (-6550 2250);
PAINT SKYBLUE (-6550 2250);
FORCEPROP 1 LAST PART_NUMBER A36096-046
J 2
(-6525 2050);
DISPLAY 0.617021 (-6525 2050);
PAINT BLUE (-6525 2050);
FORCEPROP 1 LAST LOCATION C4G7
J 2
(-6550 2300);
DISPLAY 0.617021 (-6550 2300);
PAINT AQUA (-6550 2300);
FORCEPROP 1 LAST MATERIAL EMPTY
J 2
(-6550 2100);
DISPLAY 0.617021 (-6550 2100);
PAINT RED (-6550 2100);
FORCEPROP 1 LAST TOLERANCE 10%
J 2
(-6550 2150);
DISPLAY 0.617021 (-6550 2150);
PAINT SKYBLUE (-6550 2150);
FORCEPROP 1 LAST VOLTAGE 50V
J 2
(-6550 2200);
DISPLAY 0.617021 (-6550 2200);
PAINT SKYBLUE (-6550 2200);
FORCEPROP 1 LASTPIN (-6500 2100) $PN 2
J 2
(-6510 2080);
DISPLAY 0.617021 (-6510 2080);
PAINT WHITE (-6510 2080);
FORCEPROP 1 LASTPIN (-6500 2300) $PN 1
J 2
(-6510 2280);
DISPLAY 0.617021 (-6510 2280);
PAINT WHITE (-6510 2280);
FORCEPROP 2 LAST ROOM PVPP_KLM_VR
J 2
(-6500 2200);
PAINT GREEN (-6500 2200);
DISPLAY INVISIBLE (-6500 2200);
FORCEPROP 2 LAST BOM_COST PVPP_KLM_VR
J 2
(-6500 2200);
PAINT WHITE (-6500 2200);
DISPLAY INVISIBLE (-6500 2200);
FORCEPROP 2 LAST CDS_LIB mstr_discrete
J 2
(-6500 2200);
PAINT MONO (-6500 2200);
DISPLAY INVISIBLE (-6500 2200);
FORCEPROP 2 LAST CDS_LOCATION C4G7
J 2
(-6550 2300);
DISPLAY 0.617021 (-6550 2300);
PAINT AQUA (-6550 2300);
DISPLAY INVISIBLE (-6550 2300);
FORCEPROP 1 LAST PATH I183
J 2
(-6550 2350);
DISPLAY 0.978723 (-6550 2350);
PAINT WHITE (-6550 2350);
DISPLAY INVISIBLE (-6550 2350);
FORCEPROP 2 LAST $SEC 1
J 2
(-6550 2400);
DISPLAY 0.680851 (-6550 2400);
PAINT MONO (-6550 2400);
DISPLAY INVISIBLE (-6550 2400);
FORCEPROP 2 LAST CDS_SEC 1
J 2
(-6550 2400);
DISPLAY 1.042553 (-6550 2400);
PAINT ORANGE (-6550 2400);
DISPLAY INVISIBLE (-6550 2400);
FORCEPROP 0 LAST REUSE_ID 1
J 2
(-6550 2400);
DISPLAY 1.042553 (-6550 2400);
PAINT ORANGE (-6550 2400);
DISPLAY INVISIBLE (-6550 2400);
FORCEPROP 0 LAST FIN VR_1P2
J 2
(-6550 2500);
PAINT ORANGE (-6550 2500);
DISPLAY INVISIBLE (-6550 2500);
FORCEADD RES..2
R 2
(-4675 1500);
FORCEPROP 1 LAST PART_NUMBER G21796-242
J 2
(-4715 1375);
DISPLAY 0.617021 (-4715 1375);
PAINT BLUE (-4715 1375);
FORCEPROP 1 LASTPIN (-4675 1400) $PN 2
J 2
(-4680 1410);
DISPLAY 0.617021 (-4680 1410);
PAINT WHITE (-4680 1410);
FORCEPROP 1 LAST WATTAGE 1/16W
J 2
(-4715 1475);
DISPLAY 0.617021 (-4715 1475);
PAINT SKYBLUE (-4715 1475);
FORCEPROP 1 LAST MATERIAL CHIP
J 2
(-4715 1425);
DISPLAY 0.617021 (-4715 1425);
PAINT SKYBLUE (-4715 1425);
FORCEPROP 1 LAST PACK_TYPE 0402
J 2
(-4715 1325);
DISPLAY 0.617021 (-4715 1325);
PAINT SKYBLUE (-4715 1325);
FORCEPROP 1 LAST TOLERANCE 1.0%
J 2
(-4720 1525);
DISPLAY 0.617021 (-4720 1525);
PAINT SKYBLUE (-4720 1525);
FORCEPROP 1 LAST VALUE 7.87K
J 2
(-4720 1575);
DISPLAY 0.617021 (-4720 1575);
PAINT SKYBLUE (-4720 1575);
FORCEPROP 1 LAST LOCATION R4G11
J 2
(-4720 1625);
DISPLAY 0.617021 (-4720 1625);
PAINT AQUA (-4720 1625);
FORCEPROP 1 LASTPIN (-4675 1600) $PN 1
J 2
(-4680 1562);
DISPLAY 0.617021 (-4680 1562);
PAINT WHITE (-4680 1562);
FORCEPROP 2 LAST ROOM PVPP_KLM_VR
J 2
(-4675 1500);
PAINT GREEN (-4675 1500);
DISPLAY INVISIBLE (-4675 1500);
FORCEPROP 2 LAST CDS_LIB mstr_discrete
J 2
(-4675 1500);
PAINT MONO (-4675 1500);
DISPLAY INVISIBLE (-4675 1500);
FORCEPROP 2 LAST BOM_COST PVPP_KLM_VR
J 2
(-4675 1500);
PAINT WHITE (-4675 1500);
DISPLAY INVISIBLE (-4675 1500);
FORCEPROP 1 LAST PATH I184
J 2
(-4725 1675);
DISPLAY 0.978723 (-4725 1675);
PAINT WHITE (-4725 1675);
DISPLAY INVISIBLE (-4725 1675);
FORCEPROP 2 LAST CDS_LOCATION R4G11
J 2
(-4720 1625);
DISPLAY 0.617021 (-4720 1625);
PAINT AQUA (-4720 1625);
DISPLAY INVISIBLE (-4720 1625);
FORCEPROP 2 LAST SEC 1
J 0
(-4725 1725);
DISPLAY 0.680851 (-4725 1725);
PAINT MONO (-4725 1725);
DISPLAY INVISIBLE (-4725 1725);
FORCEPROP 2 LAST SEC_TYPE 0402
J 0
(-4725 1725);
DISPLAY 1.021277 (-4725 1725);
PAINT ORANGE (-4725 1725);
DISPLAY INVISIBLE (-4725 1725);
FORCEADD RES..2
(-4150 1100);
FORCEPROP 1 LASTPIN (-4150 1000) $PN 2
J 0
(-4145 1010);
DISPLAY 0.617021 (-4145 1010);
PAINT WHITE (-4145 1010);
FORCEPROP 1 LASTPIN (-4150 1200) $PN 1
J 0
(-4145 1162);
DISPLAY 0.617021 (-4145 1162);
PAINT WHITE (-4145 1162);
FORCEPROP 1 LAST WATTAGE 1/16W
J 0
(-4110 1075);
DISPLAY 0.617021 (-4110 1075);
PAINT SKYBLUE (-4110 1075);
FORCEPROP 1 LAST MATERIAL CHIP
J 0
(-4110 1025);
DISPLAY 0.617021 (-4110 1025);
PAINT SKYBLUE (-4110 1025);
FORCEPROP 1 LAST PACK_TYPE 0402
J 0
(-4110 925);
DISPLAY 0.617021 (-4110 925);
PAINT SKYBLUE (-4110 925);
FORCEPROP 1 LAST TOLERANCE 1%
J 0
(-4105 1125);
DISPLAY 0.617021 (-4105 1125);
PAINT SKYBLUE (-4105 1125);
FORCEPROP 1 LAST VALUE 1.00K
J 0
(-4105 1175);
DISPLAY 0.617021 (-4105 1175);
PAINT SKYBLUE (-4105 1175);
FORCEPROP 1 LAST PART_NUMBER G21796-026
J 0
(-4110 975);
DISPLAY 0.617021 (-4110 975);
PAINT BLUE (-4110 975);
FORCEPROP 1 LAST LOCATION R4G14
J 0
(-4105 1225);
DISPLAY 0.617021 (-4105 1225);
PAINT AQUA (-4105 1225);
FORCEPROP 2 LAST CDS_LOCATION R4G14
J 0
(-4105 1225);
DISPLAY 0.617021 (-4105 1225);
PAINT AQUA (-4105 1225);
DISPLAY INVISIBLE (-4105 1225);
FORCEPROP 2 LAST CDS_LIB mstr_discrete
J 0
(-4150 1100);
PAINT MONO (-4150 1100);
DISPLAY INVISIBLE (-4150 1100);
FORCEPROP 1 LAST PATH I185
J 0
(-4100 1275);
DISPLAY 0.978723 (-4100 1275);
PAINT WHITE (-4100 1275);
DISPLAY INVISIBLE (-4100 1275);
FORCEPROP 2 LAST SEC 1
J 0
(-4100 1325);
DISPLAY 0.680851 (-4100 1325);
PAINT MONO (-4100 1325);
DISPLAY INVISIBLE (-4100 1325);
FORCEPROP 2 LAST SEC_TYPE 0402
J 0
(-4100 1325);
DISPLAY 1.042553 (-4100 1325);
PAINT ORANGE (-4100 1325);
DISPLAY INVISIBLE (-4100 1325);
FORCEPROP 2 LAST REUSE_ID 21
J 0
(-4100 1325);
DISPLAY 1.042553 (-4100 1325);
PAINT ORANGE (-4100 1325);
DISPLAY INVISIBLE (-4100 1325);
FORCEPROP 2 LAST ROOM PVPP_KLM_VR
J 0
(-4090 1265);
PAINT GREEN (-4090 1265);
DISPLAY INVISIBLE (-4090 1265);
FORCEPROP 2 LAST BOM_COST PVPP_KLM_VR
J 0
(-4090 1290);
DISPLAY 1.042553 (-4090 1290);
PAINT WHITE (-4090 1290);
DISPLAY INVISIBLE (-4090 1290);
FORCEADD P3V3_STBY..1
(-4150 1375);
FORCEPROP 3 LASTPIN (-4150 1325) SIG_NAME P3V3_STBY\g
J 0
(-4140 1335);
DISPLAY 0.659574 (-4140 1335);
PAINT MONO (-4140 1335);
DISPLAY INVISIBLE (-4140 1335);
FORCEPROP 1 LAST HDL_POWER P3V3_STBY
J 0
(-4450 1250);
DISPLAY 0.872340 (-4450 1250);
PAINT ORANGE (-4450 1250);
DISPLAY INVISIBLE (-4450 1250);
FORCEPROP 1 LAST PATH I186
J 0
(-4105 1377);
DISPLAY 0.340426 (-4105 1377);
PAINT GREEN (-4105 1377);
DISPLAY INVISIBLE (-4105 1377);
FORCEPROP 1 LAST BODY_TYPE PLUMBING
J 0
(-4195 1332);
DISPLAY 0.340426 (-4195 1332);
PAINT GREEN (-4195 1332);
DISPLAY INVISIBLE (-4195 1332);
FORCEPROP 1 LAST SIZE 1B
J 0
(-4105 1397);
DISPLAY 0.340426 (-4105 1397);
PAINT GREEN (-4105 1397);
DISPLAY INVISIBLE (-4105 1397);
FORCEPROP 2 LAST CDS_LIB mstr_symbols
J 0
(-4150 1375);
PAINT MONO (-4150 1375);
DISPLAY INVISIBLE (-4150 1375);
FORCEPROP 1 LAST VOLTAGE +3.3V
J 0
(-3950 1525);
DISPLAY 1.021277 (-3950 1525);
PAINT SKYBLUE (-3950 1525);
DISPLAY INVISIBLE (-3950 1525);
FORCEADD CAP..1
(-5525 2250);
FORCEPROP 1 LAST MATERIAL X6S
J 0
(-5475 2050);
DISPLAY 0.617021 (-5475 2050);
PAINT SKYBLUE (-5475 2050);
FORCEPROP 1 LASTPIN (-5525 2150) $PN 2
J 0
(-5515 2130);
DISPLAY 0.617021 (-5515 2130);
PAINT ORANGE (-5515 2130);
FORCEPROP 1 LASTPIN (-5525 2350) $PN 1
J 0
(-5515 2330);
DISPLAY 0.617021 (-5515 2330);
PAINT ORANGE (-5515 2330);
FORCEPROP 1 LAST PACK_TYPE 0603
J 0
(-5475 2150);
DISPLAY 0.617021 (-5475 2150);
PAINT SKYBLUE (-5475 2150);
FORCEPROP 1 LAST VOLTAGE 6.3V
J 0
(-5450 2250);
DISPLAY 0.617021 (-5450 2250);
PAINT SKYBLUE (-5450 2250);
FORCEPROP 1 LAST VALUE 4.7UF
J 0
(-5475 2300);
DISPLAY 0.617021 (-5475 2300);
PAINT SKYBLUE (-5475 2300);
FORCEPROP 1 LAST TOLERANCE 10%
J 0
(-5450 2200);
DISPLAY 0.617021 (-5450 2200);
PAINT SKYBLUE (-5450 2200);
FORCEPROP 1 LAST LOCATION C6U6
J 0
(-5475 2350);
DISPLAY 0.617021 (-5475 2350);
PAINT AQUA (-5475 2350);
FORCEPROP 1 LAST PART_NUMBER E15431-003
J 0
(-5500 2100);
DISPLAY 0.617021 (-5500 2100);
PAINT BLUE (-5500 2100);
FORCEPROP 2 LAST CDS_LIB mstr_discrete
J 0
(-5525 2250);
PAINT MONO (-5525 2250);
DISPLAY INVISIBLE (-5525 2250);
FORCEPROP 2 LAST REUSE_ID 26
J 0
(-5475 2450);
DISPLAY 1.042553 (-5475 2450);
PAINT ORANGE (-5475 2450);
DISPLAY INVISIBLE (-5475 2450);
FORCEPROP 2 LAST SEC_TYPE 0603
J 0
(-5475 2450);
DISPLAY 1.021277 (-5475 2450);
PAINT ORANGE (-5475 2450);
DISPLAY INVISIBLE (-5475 2450);
FORCEPROP 2 LAST BOM_COST PVPP_KLM_VR
J 0
(-5475 2400);
DISPLAY 1.042553 (-5475 2400);
PAINT WHITE (-5475 2400);
DISPLAY INVISIBLE (-5475 2400);
FORCEPROP 2 LAST ROOM PVPP_KLM_VR
J 0
(-5475 2375);
PAINT GREEN (-5475 2375);
DISPLAY INVISIBLE (-5475 2375);
FORCEPROP 1 LAST PATH I187
J 0
(-5475 2400);
DISPLAY 0.978723 (-5475 2400);
PAINT WHITE (-5475 2400);
DISPLAY INVISIBLE (-5475 2400);
FORCEPROP 2 LAST CDS_LOCATION C6U6
J 0
(-5475 2350);
DISPLAY 0.617021 (-5475 2350);
PAINT AQUA (-5475 2350);
DISPLAY INVISIBLE (-5475 2350);
FORCEPROP 2 LAST SEC 1
J 0
(-5475 2450);
PAINT MONO (-5475 2450);
DISPLAY INVISIBLE (-5475 2450);
FORCEADD GND..1
(-7025 3800);
FORCEPROP 3 LASTPIN (-7025 3850) SIG_NAME GND\g
J 0
(-7015 3860);
DISPLAY 0.659574 (-7015 3860);
PAINT MONO (-7015 3860);
DISPLAY INVISIBLE (-7015 3860);
FORCEPROP 2 LAST ROOM PVPP_KLM_VR
J 0
(-7600 3875);
DISPLAY 1.042553 (-7600 3875);
PAINT GREEN (-7600 3875);
DISPLAY INVISIBLE (-7600 3875);
FORCEPROP 2 LAST BOM_COST PVPP_KLM_VR
J 0
(-7875 3875);
DISPLAY 1.042553 (-7875 3875);
PAINT WHITE (-7875 3875);
DISPLAY INVISIBLE (-7875 3875);
FORCEPROP 1 LAST PATH I188
J 0
(-6950 3800);
DISPLAY 0.872340 (-6950 3800);
PAINT AQUA (-6950 3800);
DISPLAY INVISIBLE (-6950 3800);
FORCEPROP 1 LAST BODY_TYPE PLUMBING
J 0
(-7070 3757);
DISPLAY 0.340426 (-7070 3757);
PAINT GREEN (-7070 3757);
DISPLAY INVISIBLE (-7070 3757);
FORCEPROP 1 LAST SIZE 1B
J 0
(-6950 3750);
DISPLAY 0.872340 (-6950 3750);
PAINT GREEN (-6950 3750);
DISPLAY INVISIBLE (-6950 3750);
FORCEPROP 2 LAST CDS_LIB mstr_symbols
J 0
(-7025 3800);
PAINT MONO (-7025 3800);
DISPLAY INVISIBLE (-7025 3800);
FORCEPROP 1 LAST VOLTAGE 0
J 0
(-7025 3800);
PAINT SKYBLUE (-7025 3800);
DISPLAY INVISIBLE (-7025 3800);
FORCEPROP 1 LAST HDL_POWER GND
J 0
(-7025 3950);
DISPLAY 0.872340 (-7025 3950);
PAINT GREEN (-7025 3950);
DISPLAY INVISIBLE (-7025 3950);
FORCEADD CAP..1
(-7025 4000);
FORCEPROP 1 LASTPIN (-7025 3900) $PN 2
J 0
(-7015 3880);
DISPLAY 0.617021 (-7015 3880);
PAINT WHITE (-7015 3880);
FORCEPROP 1 LAST MATERIAL X6S
J 0
(-6975 3900);
DISPLAY 0.617021 (-6975 3900);
PAINT SKYBLUE (-6975 3900);
FORCEPROP 1 LAST VOLTAGE 16V
J 0
(-6975 4000);
DISPLAY 0.617021 (-6975 4000);
PAINT SKYBLUE (-6975 4000);
FORCEPROP 1 LAST PACK_TYPE 1210
J 0
(-6975 3800);
DISPLAY 0.617021 (-6975 3800);
PAINT SKYBLUE (-6975 3800);
FORCEPROP 1 LAST TOLERANCE 20%
J 0
(-6975 3950);
DISPLAY 0.617021 (-6975 3950);
PAINT SKYBLUE (-6975 3950);
FORCEPROP 1 LAST VALUE 47UF
J 0
(-6975 4050);
DISPLAY 0.617021 (-6975 4050);
PAINT SKYBLUE (-6975 4050);
FORCEPROP 1 LAST PART_NUMBER D38464-007
J 0
(-6975 3850);
DISPLAY 0.617021 (-6975 3850);
PAINT BLUE (-6975 3850);
FORCEPROP 1 LASTPIN (-7025 4100) $PN 1
J 0
(-7015 4080);
DISPLAY 0.617021 (-7015 4080);
PAINT WHITE (-7015 4080);
FORCEPROP 1 LAST LOCATION C4G5
J 0
(-6975 4100);
DISPLAY 0.617021 (-6975 4100);
PAINT AQUA (-6975 4100);
FORCEPROP 2 LAST ROOM PVPP_KLM_VR
J 0
(-7025 4000);
PAINT GREEN (-7025 4000);
DISPLAY INVISIBLE (-7025 4000);
FORCEPROP 2 LAST CDS_LIB mstr_discrete
J 0
(-7025 4000);
PAINT MONO (-7025 4000);
DISPLAY INVISIBLE (-7025 4000);
FORCEPROP 2 LAST BOM_COST PVPP_KLM_VR
J 0
(-7025 4000);
PAINT WHITE (-7025 4000);
DISPLAY INVISIBLE (-7025 4000);
FORCEPROP 1 LAST PATH I189
J 0
(-6975 4150);
DISPLAY 0.978723 (-6975 4150);
PAINT WHITE (-6975 4150);
DISPLAY INVISIBLE (-6975 4150);
FORCEPROP 2 LAST CDS_LOCATION C4G5
J 0
(-6975 4100);
DISPLAY 0.617021 (-6975 4100);
PAINT AQUA (-6975 4100);
DISPLAY INVISIBLE (-6975 4100);
FORCEPROP 2 LAST $SEC 1
J 0
(-6975 4200);
DISPLAY 0.680851 (-6975 4200);
PAINT MONO (-6975 4200);
DISPLAY INVISIBLE (-6975 4200);
FORCEPROP 2 LAST CDS_SEC 1
J 0
(-6975 4200);
DISPLAY 1.042553 (-6975 4200);
PAINT ORANGE (-6975 4200);
DISPLAY INVISIBLE (-6975 4200);
FORCEADD CAP..1
(-5000 2025);
FORCEPROP 1 LASTPIN (-5000 1925) $PN 2
J 0
(-4990 1905);
DISPLAY 0.617021 (-4990 1905);
PAINT ORANGE (-4990 1905);
FORCEPROP 1 LAST MATERIAL X7R
J 0
(-4950 1825);
DISPLAY 0.617021 (-4950 1825);
PAINT SKYBLUE (-4950 1825);
FORCEPROP 1 LAST PACK_TYPE 0402
J 0
(-4950 1925);
DISPLAY 0.617021 (-4950 1925);
PAINT SKYBLUE (-4950 1925);
FORCEPROP 1 LAST TOLERANCE 10%
J 0
(-4925 1975);
DISPLAY 0.617021 (-4925 1975);
PAINT SKYBLUE (-4925 1975);
FORCEPROP 1 LAST PART_NUMBER A36096-129
J 0
(-4975 1875);
DISPLAY 0.617021 (-4975 1875);
PAINT BLUE (-4975 1875);
FORCEPROP 1 LAST VOLTAGE 16V
J 0
(-4925 2025);
DISPLAY 0.617021 (-4925 2025);
PAINT SKYBLUE (-4925 2025);
FORCEPROP 1 LAST LOCATION C4G8
J 0
(-4950 2125);
DISPLAY 0.617021 (-4950 2125);
PAINT AQUA (-4950 2125);
FORCEPROP 1 LAST VALUE 0.027UF
J 0
(-4950 2075);
DISPLAY 0.617021 (-4950 2075);
PAINT SKYBLUE (-4950 2075);
FORCEPROP 1 LASTPIN (-5000 2125) $PN 1
J 0
(-4990 2105);
DISPLAY 0.617021 (-4990 2105);
PAINT ORANGE (-4990 2105);
FORCEPROP 2 LAST CDS_LIB mstr_discrete
J 0
(-5000 2025);
PAINT MONO (-5000 2025);
DISPLAY INVISIBLE (-5000 2025);
FORCEPROP 2 LAST SEC_TYPE 0402
J 0
(-4950 2225);
DISPLAY 1.021277 (-4950 2225);
PAINT ORANGE (-4950 2225);
DISPLAY INVISIBLE (-4950 2225);
FORCEPROP 2 LAST REUSE_ID 26
J 0
(-4950 2225);
DISPLAY 1.042553 (-4950 2225);
PAINT ORANGE (-4950 2225);
DISPLAY INVISIBLE (-4950 2225);
FORCEPROP 2 LAST BOM_COST PVPP_KLM_VR
J 0
(-4950 2175);
DISPLAY 1.042553 (-4950 2175);
PAINT WHITE (-4950 2175);
DISPLAY INVISIBLE (-4950 2175);
FORCEPROP 0 LAST SEC 1
J 0
(-4950 2175);
DISPLAY 0.680851 (-4950 2175);
PAINT MONO (-4950 2175);
DISPLAY INVISIBLE (-4950 2175);
FORCEPROP 2 LAST CDS_LOCATION C4G8
J 0
(-4950 2125);
DISPLAY 0.617021 (-4950 2125);
PAINT AQUA (-4950 2125);
DISPLAY INVISIBLE (-4950 2125);
FORCEPROP 1 LAST PATH I194
J 0
(-4950 2175);
DISPLAY 0.978723 (-4950 2175);
PAINT WHITE (-4950 2175);
DISPLAY INVISIBLE (-4950 2175);
FORCEPROP 2 LAST ROOM PVPP_KLM_VR
J 0
(-4950 2150);
PAINT GREEN (-4950 2150);
DISPLAY INVISIBLE (-4950 2150);
FORCEADD GND..1
(-4875 3675);
FORCEPROP 3 LASTPIN (-4875 3725) SIG_NAME GND\g
J 0
(-4865 3735);
DISPLAY 0.659574 (-4865 3735);
PAINT MONO (-4865 3735);
DISPLAY INVISIBLE (-4865 3735);
FORCEPROP 2 LAST BOM_COST PVPP_KLM_VR
J 0
(-5725 3750);
DISPLAY 1.042553 (-5725 3750);
PAINT WHITE (-5725 3750);
DISPLAY INVISIBLE (-5725 3750);
FORCEPROP 2 LAST ROOM PVPP_KLM_VR
J 0
(-5450 3750);
DISPLAY 1.042553 (-5450 3750);
PAINT GREEN (-5450 3750);
DISPLAY INVISIBLE (-5450 3750);
FORCEPROP 1 LAST VOLTAGE 0
J 0
(-4875 3675);
PAINT SKYBLUE (-4875 3675);
DISPLAY INVISIBLE (-4875 3675);
FORCEPROP 2 LAST CDS_LIB mstr_symbols
J 0
(-4875 3675);
PAINT MONO (-4875 3675);
DISPLAY INVISIBLE (-4875 3675);
FORCEPROP 1 LAST BODY_TYPE PLUMBING
J 0
(-4920 3632);
DISPLAY 0.340426 (-4920 3632);
PAINT GREEN (-4920 3632);
DISPLAY INVISIBLE (-4920 3632);
FORCEPROP 1 LAST HDL_POWER GND
J 0
(-4875 3825);
DISPLAY 0.872340 (-4875 3825);
PAINT GREEN (-4875 3825);
DISPLAY INVISIBLE (-4875 3825);
FORCEPROP 1 LAST PATH I195
J 0
(-4800 3675);
DISPLAY 0.872340 (-4800 3675);
PAINT AQUA (-4800 3675);
DISPLAY INVISIBLE (-4800 3675);
FORCEPROP 1 LAST SIZE 1B
J 0
(-4800 3625);
DISPLAY 0.872340 (-4800 3625);
PAINT GREEN (-4800 3625);
DISPLAY INVISIBLE (-4800 3625);
FORCEADD CAP..1
(-4875 4000);
FORCEPROP 1 LASTPIN (-4875 3900) $PN 2
J 0
(-4865 3880);
DISPLAY 0.617021 (-4865 3880);
PAINT WHITE (-4865 3880);
FORCEPROP 1 LAST VALUE 1.0UF
J 0
(-4825 4050);
DISPLAY 0.617021 (-4825 4050);
PAINT SKYBLUE (-4825 4050);
FORCEPROP 1 LAST MATERIAL X6S
J 0
(-4825 3900);
DISPLAY 0.617021 (-4825 3900);
PAINT SKYBLUE (-4825 3900);
FORCEPROP 1 LAST VOLTAGE 16V
J 0
(-4825 4000);
DISPLAY 0.617021 (-4825 4000);
PAINT SKYBLUE (-4825 4000);
FORCEPROP 1 LAST TOLERANCE 10%
J 0
(-4825 3950);
DISPLAY 0.617021 (-4825 3950);
PAINT SKYBLUE (-4825 3950);
FORCEPROP 1 LAST PACK_TYPE 0402
J 0
(-4825 3800);
DISPLAY 0.617021 (-4825 3800);
PAINT SKYBLUE (-4825 3800);
FORCEPROP 1 LAST PART_NUMBER D97712-011
J 0
(-4825 3850);
DISPLAY 0.617021 (-4825 3850);
PAINT BLUE (-4825 3850);
FORCEPROP 1 LASTPIN (-4875 4100) $PN 1
J 0
(-4865 4080);
DISPLAY 0.617021 (-4865 4080);
PAINT WHITE (-4865 4080);
FORCEPROP 1 LAST LOCATION C4G4
J 0
(-4825 4100);
DISPLAY 0.617021 (-4825 4100);
PAINT AQUA (-4825 4100);
FORCEPROP 2 LAST ROOM PVPP_KLM_VR
J 0
(-4875 4000);
PAINT GREEN (-4875 4000);
DISPLAY INVISIBLE (-4875 4000);
FORCEPROP 2 LAST CDS_LIB mstr_discrete
J 0
(-4875 4000);
PAINT MONO (-4875 4000);
DISPLAY INVISIBLE (-4875 4000);
FORCEPROP 2 LAST BOM_COST PVPP_KLM_VR
J 0
(-4875 4000);
PAINT WHITE (-4875 4000);
DISPLAY INVISIBLE (-4875 4000);
FORCEPROP 1 LAST PATH I196
J 0
(-4825 4150);
DISPLAY 0.978723 (-4825 4150);
PAINT WHITE (-4825 4150);
DISPLAY INVISIBLE (-4825 4150);
FORCEPROP 2 LAST CDS_LOCATION C4G4
J 0
(-4825 4100);
DISPLAY 0.617021 (-4825 4100);
PAINT AQUA (-4825 4100);
DISPLAY INVISIBLE (-4825 4100);
FORCEPROP 2 LAST $SEC 1
J 0
(-4825 4200);
DISPLAY 0.680851 (-4825 4200);
PAINT MONO (-4825 4200);
DISPLAY INVISIBLE (-4825 4200);
FORCEPROP 2 LAST CDS_SEC 1
J 0
(-4825 4200);
DISPLAY 1.042553 (-4825 4200);
PAINT ORANGE (-4825 4200);
DISPLAY INVISIBLE (-4825 4200);
FORCEPROP 0 LAST REUSE_ID 1
J 0
(-4825 4200);
DISPLAY 1.042553 (-4825 4200);
PAINT ORANGE (-4825 4200);
DISPLAY INVISIBLE (-4825 4200);
FORCEPROP 0 LAST FIN VR_1P2
J 0
(-4825 4300);
PAINT ORANGE (-4825 4300);
DISPLAY INVISIBLE (-4825 4300);
FORCEADD P12V_STBY..1
(-7400 4350);
FORCEPROP 3 LASTPIN (-7400 4300) SIG_NAME P12V_STBY\g
J 0
(-7390 4310);
DISPLAY 0.659574 (-7390 4310);
PAINT MONO (-7390 4310);
DISPLAY INVISIBLE (-7390 4310);
FORCEPROP 1 LAST HDL_POWER P12V_STBY
J 0
(-7700 4225);
DISPLAY 0.872340 (-7700 4225);
PAINT ORANGE (-7700 4225);
DISPLAY INVISIBLE (-7700 4225);
FORCEPROP 1 LAST BODY_TYPE PLUMBING
J 0
(-7445 4307);
DISPLAY 0.340426 (-7445 4307);
PAINT GREEN (-7445 4307);
DISPLAY INVISIBLE (-7445 4307);
FORCEPROP 1 LAST VOLTAGE 12.0V
J 0
(-7445 4307);
DISPLAY 0.340426 (-7445 4307);
PAINT SKYBLUE (-7445 4307);
DISPLAY INVISIBLE (-7445 4307);
FORCEPROP 1 LAST PATH I197
J 0
(-7355 4352);
DISPLAY 0.340426 (-7355 4352);
PAINT GREEN (-7355 4352);
DISPLAY INVISIBLE (-7355 4352);
FORCEPROP 2 LAST CDS_LIB mstr_symbols
J 0
(-7400 4350);
PAINT ORANGE (-7400 4350);
DISPLAY INVISIBLE (-7400 4350);
FORCEPROP 1 LAST SIZE 1B
J 0
(-7355 4372);
DISPLAY 0.340426 (-7355 4372);
PAINT GREEN (-7355 4372);
DISPLAY INVISIBLE (-7355 4372);
FORCEADD FERRITE..1
(-7225 4150);
FORCEPROP 1 LAST VALUE 22
J 2
(-7245 4050);
DISPLAY 0.617021 (-7245 4050);
PAINT SKYBLUE (-7245 4050);
FORCEPROP 1 LAST MATERIAL FB
J 0
(-7220 4050);
DISPLAY 0.617021 (-7220 4050);
PAINT SKYBLUE (-7220 4050);
FORCEPROP 1 LAST PACK_TYPE SM
J 0
(-7145 4050);
DISPLAY 0.617021 (-7145 4050);
PAINT SKYBLUE (-7145 4050);
FORCEPROP 1 LAST LOCATION FB4G1
J 0
(-7320 4205);
DISPLAY 0.617021 (-7320 4205);
PAINT AQUA (-7320 4205);
FORCEPROP 1 LASTPIN (-7325 4150) $PN 1
J 2
(-7290 4160);
DISPLAY 0.617021 (-7290 4160);
PAINT WHITE (-7290 4160);
FORCEPROP 1 LAST PART_NUMBER 656554-051
J 0
(-7320 4265);
DISPLAY 0.617021 (-7320 4265);
PAINT BLUE (-7320 4265);
FORCEPROP 1 LASTPIN (-7125 4150) $PN 2
J 0
(-7145 4160);
DISPLAY 0.617021 (-7145 4160);
PAINT WHITE (-7145 4160);
FORCEPROP 2 LAST CDS_LOCATION FB4G1
J 0
(-7320 4205);
DISPLAY 0.617021 (-7320 4205);
PAINT AQUA (-7320 4205);
DISPLAY INVISIBLE (-7320 4205);
FORCEPROP 0 LAST TOLERANCE 1%
J 0
(-7300 4300);
PAINT SKYBLUE (-7300 4300);
DISPLAY INVISIBLE (-7300 4300);
FORCEPROP 1 LAST PATH I198
J 0
(-7320 4315);
DISPLAY 0.872340 (-7320 4315);
PAINT PURPLE (-7320 4315);
DISPLAY INVISIBLE (-7320 4315);
FORCEPROP 2 LAST CDS_LIB mstr_discrete
J 0
(-7225 4150);
PAINT MONO (-7225 4150);
DISPLAY INVISIBLE (-7225 4150);
FORCEPROP 2 LAST ROOM PVPP_KLM_VR
J 0
(-7300 4300);
DISPLAY 1.659574 (-7300 4300);
PAINT GREEN (-7300 4300);
DISPLAY INVISIBLE (-7300 4300);
FORCEPROP 2 LAST SEC_TYPE SM
J 0
(-7300 4375);
DISPLAY 1.659574 (-7300 4375);
PAINT ORANGE (-7300 4375);
DISPLAY INVISIBLE (-7300 4375);
FORCEPROP 2 LAST SEC 1
J 0
(-7300 4375);
DISPLAY 1.106383 (-7300 4375);
PAINT MONO (-7300 4375);
DISPLAY INVISIBLE (-7300 4375);
FORCEADD RES..1
(-4000 4050);
FORCEPROP 1 LAST VALUE 0.0
J 2
(-4100 3925);
DISPLAY 0.617021 (-4100 3925);
PAINT SKYBLUE (-4100 3925);
FORCEPROP 1 LAST WATTAGE 1/16W
J 2
(-4025 3875);
DISPLAY 0.617021 (-4025 3875);
PAINT SKYBLUE (-4025 3875);
FORCEPROP 1 LAST PART_NUMBER G21497-005
J 0
(-4150 3975);
DISPLAY 0.617021 (-4150 3975);
PAINT BLUE (-4150 3975);
FORCEPROP 1 LASTPIN (-4100 4050) $PN 1
J 0
(-4088 4062);
DISPLAY 0.617021 (-4088 4062);
PAINT WHITE (-4088 4062);
FORCEPROP 1 LAST TOLERANCE 5%
J 0
(-4050 3925);
DISPLAY 0.617021 (-4050 3925);
PAINT SKYBLUE (-4050 3925);
FORCEPROP 1 LAST MATERIAL CHIP
J 0
(-4000 3875);
DISPLAY 0.617021 (-4000 3875);
PAINT SKYBLUE (-4000 3875);
FORCEPROP 1 LASTPIN (-3900 4050) $PN 2
J 0
(-3938 4062);
DISPLAY 0.617021 (-3938 4062);
PAINT WHITE (-3938 4062);
FORCEPROP 1 LAST PACK_TYPE 0402
J 0
(-3950 3925);
DISPLAY 0.617021 (-3950 3925);
PAINT SKYBLUE (-3950 3925);
FORCEPROP 1 LAST LOCATION R4G24
J 0
(-4050 4100);
DISPLAY 0.617021 (-4050 4100);
PAINT AQUA (-4050 4100);
FORCEPROP 2 LAST ROOM PVPP_KLM_VR
J 0
(-4000 4050);
PAINT GREEN (-4000 4050);
DISPLAY INVISIBLE (-4000 4050);
FORCEPROP 2 LAST BOM_COST PVPP_KLM_VR
J 0
(-4000 4050);
PAINT WHITE (-4000 4050);
DISPLAY INVISIBLE (-4000 4050);
FORCEPROP 2 LAST CDS_LIB mstr_discrete
J 0
(-4000 4050);
PAINT MONO (-4000 4050);
DISPLAY INVISIBLE (-4000 4050);
FORCEPROP 1 LAST PATH I199
J 0
(-4050 4200);
DISPLAY 0.978723 (-4050 4200);
PAINT WHITE (-4050 4200);
DISPLAY INVISIBLE (-4050 4200);
FORCEPROP 2 LAST $SEC 1
J 0
(-4050 4250);
DISPLAY 0.680851 (-4050 4250);
PAINT MONO (-4050 4250);
DISPLAY INVISIBLE (-4050 4250);
FORCEPROP 2 LAST CDS_SEC 1
J 0
(-4050 4250);
DISPLAY 1.042553 (-4050 4250);
PAINT ORANGE (-4050 4250);
DISPLAY INVISIBLE (-4050 4250);
FORCEPROP 2 LAST REUSE_ID 13
J 0
(-4050 4250);
DISPLAY 1.042553 (-4050 4250);
PAINT ORANGE (-4050 4250);
DISPLAY INVISIBLE (-4050 4250);
FORCEPROP 0 LAST SPOF TRUE
J 0
(-4050 4200);
DISPLAY 1.021277 (-4050 4200);
PAINT ORANGE (-4050 4200);
DISPLAY INVISIBLE (-4050 4200);
FORCEADD GND..1
(-3800 325);
FORCEPROP 3 LASTPIN (-3800 375) SIG_NAME GND\g
J 0
(-3790 385);
DISPLAY 0.659574 (-3790 385);
PAINT MONO (-3790 385);
DISPLAY INVISIBLE (-3790 385);
FORCEPROP 2 LAST BOM_COST PVPP_KLM_VR
J 0
(-4700 475);
DISPLAY 1.042553 (-4700 475);
PAINT WHITE (-4700 475);
DISPLAY INVISIBLE (-4700 475);
FORCEPROP 2 LAST ROOM PVPP_KLM_VR
J 0
(-4450 475);
PAINT GREEN (-4450 475);
DISPLAY INVISIBLE (-4450 475);
FORCEPROP 1 LAST BODY_TYPE PLUMBING
J 0
(-3845 282);
DISPLAY 0.340426 (-3845 282);
PAINT GREEN (-3845 282);
DISPLAY INVISIBLE (-3845 282);
FORCEPROP 1 LAST PATH I200
J 0
(-3725 325);
DISPLAY 0.872340 (-3725 325);
PAINT AQUA (-3725 325);
DISPLAY INVISIBLE (-3725 325);
FORCEPROP 1 LAST SIZE 1B
J 0
(-3725 350);
DISPLAY 0.893617 (-3725 350);
PAINT GREEN (-3725 350);
DISPLAY INVISIBLE (-3725 350);
FORCEPROP 2 LAST CDS_LIB mstr_symbols
J 0
(-3800 400);
PAINT MONO (-3800 400);
DISPLAY INVISIBLE (-3800 400);
FORCEPROP 1 LAST VOLTAGE 0
J 0
(-3800 400);
PAINT SKYBLUE (-3800 400);
DISPLAY INVISIBLE (-3800 400);
FORCEPROP 1 LAST HDL_POWER GND
J 0
(-3800 550);
DISPLAY 0.893617 (-3800 550);
PAINT GREEN (-3800 550);
DISPLAY INVISIBLE (-3800 550);
FORCEADD CAP..1
(-3800 575);
FORCEPROP 1 LASTPIN (-3800 475) $PN 2
J 0
(-3790 455);
DISPLAY 0.617021 (-3790 455);
PAINT WHITE (-3790 455);
FORCEPROP 1 LAST MATERIAL X7R
J 0
(-3750 475);
DISPLAY 0.617021 (-3750 475);
PAINT SKYBLUE (-3750 475);
FORCEPROP 1 LASTPIN (-3800 675) $PN 1
J 0
(-3790 655);
DISPLAY 0.617021 (-3790 655);
PAINT WHITE (-3790 655);
FORCEPROP 1 LAST VOLTAGE 50V
J 0
(-3750 575);
DISPLAY 0.617021 (-3750 575);
PAINT SKYBLUE (-3750 575);
FORCEPROP 1 LAST LOCATION C4G9
J 0
(-3750 675);
DISPLAY 0.617021 (-3750 675);
PAINT AQUA (-3750 675);
FORCEPROP 1 LAST TOLERANCE 10%
J 0
(-3750 525);
DISPLAY 0.617021 (-3750 525);
PAINT SKYBLUE (-3750 525);
FORCEPROP 1 LAST PACK_TYPE 0402LF
J 0
(-3750 425);
DISPLAY 0.617021 (-3750 425);
PAINT SKYBLUE (-3750 425);
FORCEPROP 1 LAST VALUE 1000PF
J 0
(-3750 625);
DISPLAY 0.617021 (-3750 625);
PAINT SKYBLUE (-3750 625);
FORCEPROP 1 LAST PART_NUMBER A36096-046
J 0
(-3750 375);
DISPLAY 0.617021 (-3750 375);
PAINT BLUE (-3750 375);
FORCEPROP 2 LAST ROOM PVPP_KLM_VR
J 0
(-3800 575);
PAINT GREEN (-3800 575);
DISPLAY INVISIBLE (-3800 575);
FORCEPROP 1 LAST PATH I201
J 0
(-3750 725);
DISPLAY 0.978723 (-3750 725);
PAINT WHITE (-3750 725);
DISPLAY INVISIBLE (-3750 725);
FORCEPROP 2 LAST CDS_LOCATION C4G9
J 0
(-3750 675);
DISPLAY 0.617021 (-3750 675);
PAINT AQUA (-3750 675);
DISPLAY INVISIBLE (-3750 675);
FORCEPROP 2 LAST CDS_LIB mstr_discrete
J 2
(-3800 575);
PAINT MONO (-3800 575);
DISPLAY INVISIBLE (-3800 575);
FORCEPROP 2 LAST BOM_COST PVPP_KLM_VR
J 0
(-3800 575);
PAINT WHITE (-3800 575);
DISPLAY INVISIBLE (-3800 575);
FORCEPROP 2 LAST REUSE_ID 17
J 0
(-3750 775);
DISPLAY 1.042553 (-3750 775);
PAINT ORANGE (-3750 775);
DISPLAY INVISIBLE (-3750 775);
FORCEPROP 2 LAST CDS_SEC 1
J 2
(-3750 775);
DISPLAY 1.042553 (-3750 775);
PAINT ORANGE (-3750 775);
DISPLAY INVISIBLE (-3750 775);
FORCEPROP 2 LAST $SEC 1
J 2
(-3750 775);
DISPLAY 0.680851 (-3750 775);
PAINT MONO (-3750 775);
DISPLAY INVISIBLE (-3750 775);
FORCEADD OFFPAGE..2
(-2550 825);
FORCEPROP 2 LAST $XR0 190 
J 0
(-2361 825);
DISPLAY 0.638298 (-2361 825);
PAINT MONO (-2361 825);
FORCEPROP 2 LAST BOM_COST PVPP_KLM_VR
J 0
(-3250 900);
DISPLAY 1.042553 (-3250 900);
PAINT WHITE (-3250 900);
DISPLAY INVISIBLE (-3250 900);
FORCEPROP 1 LAST COMMENT_BODY TRUE
J 0
(-2595 730);
DISPLAY 0.872340 (-2595 730);
PAINT PEACH (-2595 730);
DISPLAY INVISIBLE (-2595 730);
FORCEPROP 2 LAST ROOM PVPP_KLM_VR
J 0
(-2975 900);
DISPLAY 1.042553 (-2975 900);
PAINT GREEN (-2975 900);
DISPLAY INVISIBLE (-2975 900);
FORCEPROP 2 LAST CDS_LIB mstr_standard
J 2
(-2550 825);
PAINT MONO (-2550 825);
DISPLAY INVISIBLE (-2550 825);
FORCEPROP 0 LAST TOLERANCE 1%
J 0
(-2375 900);
PAINT SKYBLUE (-2375 900);
DISPLAY INVISIBLE (-2375 900);
FORCEPROP 2 LAST PATH I202
J 0
(-2250 875);
DISPLAY 1.021277 (-2250 875);
PAINT ORANGE (-2250 875);
DISPLAY INVISIBLE (-2250 875);
FORCEPROP 1 LAST OFFPAGE TRUE
J 0
(-2225 700);
PAINT GREEN (-2225 700);
DISPLAY INVISIBLE (-2225 700);
FORCEADD GND..1
(-3000 1775);
FORCEPROP 3 LASTPIN (-3000 1825) SIG_NAME GND\g
J 0
(-2990 1835);
DISPLAY 0.659574 (-2990 1835);
PAINT MONO (-2990 1835);
DISPLAY INVISIBLE (-2990 1835);
FORCEPROP 2 LAST BOM_COST PVPP_KLM_VR
J 0
(-3900 1925);
DISPLAY 1.042553 (-3900 1925);
PAINT WHITE (-3900 1925);
DISPLAY INVISIBLE (-3900 1925);
FORCEPROP 2 LAST ROOM PVPP_KLM_VR
J 0
(-3650 1925);
PAINT GREEN (-3650 1925);
DISPLAY INVISIBLE (-3650 1925);
FORCEPROP 1 LAST BODY_TYPE PLUMBING
J 0
(-3045 1732);
DISPLAY 0.340426 (-3045 1732);
PAINT GREEN (-3045 1732);
DISPLAY INVISIBLE (-3045 1732);
FORCEPROP 1 LAST PATH I203
J 0
(-2925 1775);
DISPLAY 0.872340 (-2925 1775);
PAINT AQUA (-2925 1775);
DISPLAY INVISIBLE (-2925 1775);
FORCEPROP 2 LAST CDS_LIB mstr_symbols
J 0
(-3000 1775);
PAINT MONO (-3000 1775);
DISPLAY INVISIBLE (-3000 1775);
FORCEPROP 1 LAST VOLTAGE 0
J 0
(-3000 1850);
PAINT SKYBLUE (-3000 1850);
DISPLAY INVISIBLE (-3000 1850);
FORCEPROP 1 LAST HDL_POWER GND
J 0
(-3000 2000);
DISPLAY 0.893617 (-3000 2000);
PAINT GREEN (-3000 2000);
DISPLAY INVISIBLE (-3000 2000);
FORCEPROP 1 LAST SIZE 1B
J 0
(-2925 1800);
DISPLAY 0.893617 (-2925 1800);
PAINT GREEN (-2925 1800);
DISPLAY INVISIBLE (-2925 1800);
FORCEADD GND..1
(-2575 3000);
FORCEPROP 3 LASTPIN (-2575 3050) SIG_NAME GND\g
J 0
(-2565 3060);
DISPLAY 0.659574 (-2565 3060);
PAINT MONO (-2565 3060);
DISPLAY INVISIBLE (-2565 3060);
FORCEPROP 2 LAST BOM_COST PVPP_KLM_VR
J 0
(-3475 3150);
DISPLAY 1.042553 (-3475 3150);
PAINT WHITE (-3475 3150);
DISPLAY INVISIBLE (-3475 3150);
FORCEPROP 2 LAST ROOM PVPP_KLM_VR
J 0
(-3225 3150);
PAINT GREEN (-3225 3150);
DISPLAY INVISIBLE (-3225 3150);
FORCEPROP 1 LAST BODY_TYPE PLUMBING
J 0
(-2620 2957);
DISPLAY 0.340426 (-2620 2957);
PAINT GREEN (-2620 2957);
DISPLAY INVISIBLE (-2620 2957);
FORCEPROP 1 LAST PATH I207
J 0
(-2500 3000);
DISPLAY 0.872340 (-2500 3000);
PAINT AQUA (-2500 3000);
DISPLAY INVISIBLE (-2500 3000);
FORCEPROP 1 LAST SIZE 1B
J 0
(-2500 3025);
DISPLAY 0.893617 (-2500 3025);
PAINT GREEN (-2500 3025);
DISPLAY INVISIBLE (-2500 3025);
FORCEPROP 2 LAST CDS_LIB mstr_symbols
J 0
(-2575 3075);
PAINT MONO (-2575 3075);
DISPLAY INVISIBLE (-2575 3075);
FORCEPROP 1 LAST VOLTAGE 0
J 0
(-2575 3075);
PAINT SKYBLUE (-2575 3075);
DISPLAY INVISIBLE (-2575 3075);
FORCEPROP 1 LAST HDL_POWER GND
J 0
(-2575 3225);
DISPLAY 0.893617 (-2575 3225);
PAINT GREEN (-2575 3225);
DISPLAY INVISIBLE (-2575 3225);
FORCEADD RES..2
(-2575 3200);
FORCEPROP 1 LAST PART_NUMBER G21497-016
J 0
(-2460 3025);
DISPLAY 0.617021 (-2460 3025);
PAINT BLUE (-2460 3025);
FORCEPROP 1 LASTPIN (-2575 3300) $PN 1
J 0
(-2570 3262);
DISPLAY 0.617021 (-2570 3262);
PAINT WHITE (-2570 3262);
FORCEPROP 1 LASTPIN (-2575 3100) $PN 2
J 0
(-2570 3110);
DISPLAY 0.617021 (-2570 3110);
PAINT WHITE (-2570 3110);
FORCEPROP 1 LAST WATTAGE 1/16W
J 0
(-2460 3125);
DISPLAY 0.617021 (-2460 3125);
PAINT SKYBLUE (-2460 3125);
FORCEPROP 1 LAST PACK_TYPE 0402
J 0
(-2460 3075);
DISPLAY 0.617021 (-2460 3075);
PAINT SKYBLUE (-2460 3075);
FORCEPROP 1 LAST TOLERANCE 5%
J 0
(-2455 3225);
DISPLAY 0.617021 (-2455 3225);
PAINT SKYBLUE (-2455 3225);
FORCEPROP 1 LAST VALUE 2.2
J 0
(-2455 3275);
DISPLAY 0.617021 (-2455 3275);
PAINT SKYBLUE (-2455 3275);
FORCEPROP 1 LAST LOCATION R4F6
J 0
(-2530 3300);
DISPLAY 0.617021 (-2530 3300);
PAINT AQUA (-2530 3300);
FORCEPROP 1 LAST MATERIAL EMPTY
J 0
(-2460 3175);
DISPLAY 0.617021 (-2460 3175);
PAINT RED (-2460 3175);
FORCEPROP 2 LAST CDS_LIB mstr_discrete
J 0
(-2575 3200);
PAINT MONO (-2575 3200);
DISPLAY INVISIBLE (-2575 3200);
FORCEPROP 2 LAST CDS_LOCATION R4F6
J 0
(-2530 3300);
DISPLAY 0.617021 (-2530 3300);
PAINT AQUA (-2530 3300);
DISPLAY INVISIBLE (-2530 3300);
FORCEPROP 2 LAST ROOM PVPP_KLM_VR
J 0
(-2525 3350);
PAINT GREEN (-2525 3350);
DISPLAY INVISIBLE (-2525 3350);
FORCEPROP 1 LAST PATH I208
J 0
(-2525 3375);
DISPLAY 0.978723 (-2525 3375);
PAINT WHITE (-2525 3375);
DISPLAY INVISIBLE (-2525 3375);
FORCEPROP 2 LAST $SEC 1
J 0
(-2525 3425);
DISPLAY 0.680851 (-2525 3425);
PAINT MONO (-2525 3425);
DISPLAY INVISIBLE (-2525 3425);
FORCEPROP 2 LAST BOM_COST PVPP_KLM_VR
J 0
(-2525 3375);
DISPLAY 1.042553 (-2525 3375);
PAINT WHITE (-2525 3375);
DISPLAY INVISIBLE (-2525 3375);
FORCEPROP 2 LAST CDS_SEC 1
J 0
(-2525 3425);
DISPLAY 1.042553 (-2525 3425);
PAINT ORANGE (-2525 3425);
DISPLAY INVISIBLE (-2525 3425);
FORCEPROP 2 LAST REUSE_ID 29
J 0
(-2525 3425);
DISPLAY 1.042553 (-2525 3425);
PAINT ORANGE (-2525 3425);
DISPLAY INVISIBLE (-2525 3425);
FORCEADD CAP..1
(-2575 3550);
FORCEPROP 1 LASTPIN (-2575 3650) $PN 1
J 0
(-2565 3630);
DISPLAY 0.617021 (-2565 3630);
PAINT WHITE (-2565 3630);
FORCEPROP 1 LASTPIN (-2575 3450) $PN 2
J 0
(-2565 3430);
DISPLAY 0.617021 (-2565 3430);
PAINT WHITE (-2565 3430);
FORCEPROP 1 LAST VOLTAGE 50V
J 0
(-2450 3550);
DISPLAY 0.617021 (-2450 3550);
PAINT SKYBLUE (-2450 3550);
FORCEPROP 1 LAST TOLERANCE 10%
J 0
(-2450 3500);
DISPLAY 0.617021 (-2450 3500);
PAINT SKYBLUE (-2450 3500);
FORCEPROP 1 LAST PACK_TYPE 0402LF
J 0
(-2450 3450);
DISPLAY 0.617021 (-2450 3450);
PAINT SKYBLUE (-2450 3450);
FORCEPROP 1 LAST PART_NUMBER A36096-091
J 0
(-2450 3400);
DISPLAY 0.617021 (-2450 3400);
PAINT BLUE (-2450 3400);
FORCEPROP 1 LAST MATERIAL EMPTY
J 0
(-2350 3525);
DISPLAY 0.617021 (-2350 3525);
PAINT RED (-2350 3525);
FORCEPROP 1 LAST LOCATION C4F12
J 0
(-2475 3650);
DISPLAY 0.617021 (-2475 3650);
PAINT AQUA (-2475 3650);
FORCEPROP 1 LAST VALUE 3300PF
J 0
(-2450 3600);
DISPLAY 0.617021 (-2450 3600);
PAINT SKYBLUE (-2450 3600);
FORCEPROP 2 LAST CDS_LIB mstr_discrete
J 0
(-2575 3550);
PAINT MONO (-2575 3550);
DISPLAY INVISIBLE (-2575 3550);
FORCEPROP 2 LAST ROOM PVPP_KLM_VR
J 0
(-2525 3675);
PAINT GREEN (-2525 3675);
DISPLAY INVISIBLE (-2525 3675);
FORCEPROP 1 LAST PATH I209
J 0
(-2525 3700);
DISPLAY 0.978723 (-2525 3700);
PAINT WHITE (-2525 3700);
DISPLAY INVISIBLE (-2525 3700);
FORCEPROP 2 LAST CDS_LOCATION C4F12
J 0
(-2475 3650);
DISPLAY 0.617021 (-2475 3650);
PAINT AQUA (-2475 3650);
DISPLAY INVISIBLE (-2475 3650);
FORCEPROP 2 LAST $SEC 1
J 0
(-2525 3750);
DISPLAY 0.680851 (-2525 3750);
PAINT MONO (-2525 3750);
DISPLAY INVISIBLE (-2525 3750);
FORCEPROP 2 LAST CDS_SEC 1
J 0
(-2525 3750);
DISPLAY 1.042553 (-2525 3750);
PAINT ORANGE (-2525 3750);
DISPLAY INVISIBLE (-2525 3750);
FORCEPROP 2 LAST REUSE_ID 26
J 0
(-2525 3750);
DISPLAY 1.042553 (-2525 3750);
PAINT ORANGE (-2525 3750);
DISPLAY INVISIBLE (-2525 3750);
FORCEPROP 2 LAST BOM_COST PVPP_KLM_VR
J 0
(-2525 3700);
DISPLAY 1.042553 (-2525 3700);
PAINT WHITE (-2525 3700);
DISPLAY INVISIBLE (-2525 3700);
FORCEADD GND..1
(-2000 3275);
FORCEPROP 3 LASTPIN (-2000 3325) SIG_NAME GND\g
J 0
(-1990 3335);
DISPLAY 0.659574 (-1990 3335);
PAINT MONO (-1990 3335);
DISPLAY INVISIBLE (-1990 3335);
FORCEPROP 2 LAST BOM_COST PVPP_KLM_VR
J 0
(-2850 3350);
DISPLAY 1.042553 (-2850 3350);
PAINT WHITE (-2850 3350);
DISPLAY INVISIBLE (-2850 3350);
FORCEPROP 2 LAST ROOM PVPP_KLM_VR
J 0
(-2575 3350);
DISPLAY 1.042553 (-2575 3350);
PAINT GREEN (-2575 3350);
DISPLAY INVISIBLE (-2575 3350);
FORCEPROP 1 LAST PATH I210
J 0
(-1925 3275);
DISPLAY 0.872340 (-1925 3275);
PAINT AQUA (-1925 3275);
DISPLAY INVISIBLE (-1925 3275);
FORCEPROP 1 LAST BODY_TYPE PLUMBING
J 0
(-2045 3232);
DISPLAY 0.340426 (-2045 3232);
PAINT GREEN (-2045 3232);
DISPLAY INVISIBLE (-2045 3232);
FORCEPROP 2 LAST CDS_LIB mstr_symbols
J 0
(-2000 3275);
PAINT MONO (-2000 3275);
DISPLAY INVISIBLE (-2000 3275);
FORCEPROP 1 LAST SIZE 1B
J 0
(-1925 3225);
DISPLAY 0.872340 (-1925 3225);
PAINT GREEN (-1925 3225);
DISPLAY INVISIBLE (-1925 3225);
FORCEPROP 1 LAST VOLTAGE 0
J 0
(-2000 3275);
PAINT SKYBLUE (-2000 3275);
DISPLAY INVISIBLE (-2000 3275);
FORCEPROP 1 LAST HDL_POWER GND
J 0
(-2000 3425);
DISPLAY 0.872340 (-2000 3425);
PAINT GREEN (-2000 3425);
DISPLAY INVISIBLE (-2000 3425);
FORCEADD RES..2
(-2000 3525);
FORCEPROP 1 LASTPIN (-2000 3425) $PN 2
J 0
(-1995 3435);
DISPLAY 0.617021 (-1995 3435);
PAINT WHITE (-1995 3435);
FORCEPROP 1 LAST TOLERANCE 1%
J 0
(-1955 3550);
DISPLAY 0.617021 (-1955 3550);
PAINT SKYBLUE (-1955 3550);
FORCEPROP 1 LAST PACK_TYPE 0603
J 0
(-1960 3350);
DISPLAY 0.617021 (-1960 3350);
PAINT SKYBLUE (-1960 3350);
FORCEPROP 1 LAST MATERIAL CHIP
J 0
(-1960 3450);
DISPLAY 0.617021 (-1960 3450);
PAINT SKYBLUE (-1960 3450);
FORCEPROP 1 LAST WATTAGE 1/10W
J 0
(-1960 3500);
DISPLAY 0.617021 (-1960 3500);
PAINT SKYBLUE (-1960 3500);
FORCEPROP 1 LAST PART_NUMBER G22026-003
J 0
(-1960 3400);
DISPLAY 0.617021 (-1960 3400);
PAINT BLUE (-1960 3400);
FORCEPROP 1 LASTPIN (-2000 3625) $PN 1
J 0
(-1995 3587);
DISPLAY 0.617021 (-1995 3587);
PAINT WHITE (-1995 3587);
FORCEPROP 1 LAST VALUE 120.0
J 0
(-1955 3600);
DISPLAY 0.617021 (-1955 3600);
PAINT SKYBLUE (-1955 3600);
FORCEPROP 1 LAST LOCATION R4G6
J 0
(-1955 3650);
DISPLAY 0.617021 (-1955 3650);
PAINT AQUA (-1955 3650);
FORCEPROP 2 LAST CDS_LIB mstr_discrete
J 0
(-2000 3525);
PAINT MONO (-2000 3525);
DISPLAY INVISIBLE (-2000 3525);
FORCEPROP 2 LAST CDS_LOCATION R4G6
J 0
(-1955 3650);
DISPLAY 0.617021 (-1955 3650);
PAINT AQUA (-1955 3650);
DISPLAY INVISIBLE (-1955 3650);
FORCEPROP 2 LAST ROOM PVPP_KLM_VR
J 0
(-1955 3680);
PAINT GREEN (-1955 3680);
DISPLAY INVISIBLE (-1955 3680);
FORCEPROP 1 LAST PATH I211
J 0
(-1950 3700);
DISPLAY 0.978723 (-1950 3700);
PAINT WHITE (-1950 3700);
DISPLAY INVISIBLE (-1950 3700);
FORCEPROP 2 LAST BOM_COST PVPP_KLM_VR
J 0
(-1955 3705);
DISPLAY 1.042553 (-1955 3705);
PAINT WHITE (-1955 3705);
DISPLAY INVISIBLE (-1955 3705);
FORCEPROP 2 LAST $SEC 1
J 0
(-1950 3750);
DISPLAY 0.680851 (-1950 3750);
PAINT MONO (-1950 3750);
DISPLAY INVISIBLE (-1950 3750);
FORCEPROP 2 LAST CDS_SEC 1
J 0
(-1950 3750);
DISPLAY 1.042553 (-1950 3750);
PAINT ORANGE (-1950 3750);
DISPLAY INVISIBLE (-1950 3750);
FORCEPROP 2 LAST REUSE_ID 34
J 0
(-1950 3750);
DISPLAY 1.042553 (-1950 3750);
PAINT ORANGE (-1950 3750);
DISPLAY INVISIBLE (-1950 3750);
FORCEADD GND..1
(-1675 3300);
FORCEPROP 3 LASTPIN (-1675 3350) SIG_NAME GND\g
J 0
(-1665 3360);
DISPLAY 0.659574 (-1665 3360);
PAINT MONO (-1665 3360);
DISPLAY INVISIBLE (-1665 3360);
FORCEPROP 2 LAST BOM_COST PVPP_KLM_VR
J 0
(-2525 3375);
DISPLAY 1.042553 (-2525 3375);
PAINT WHITE (-2525 3375);
DISPLAY INVISIBLE (-2525 3375);
FORCEPROP 2 LAST ROOM PVPP_KLM_VR
J 0
(-2250 3375);
DISPLAY 1.042553 (-2250 3375);
PAINT GREEN (-2250 3375);
DISPLAY INVISIBLE (-2250 3375);
FORCEPROP 1 LAST BODY_TYPE PLUMBING
J 0
(-1720 3257);
DISPLAY 0.340426 (-1720 3257);
PAINT GREEN (-1720 3257);
DISPLAY INVISIBLE (-1720 3257);
FORCEPROP 1 LAST SIZE 1B
J 0
(-1600 3250);
DISPLAY 0.872340 (-1600 3250);
PAINT GREEN (-1600 3250);
DISPLAY INVISIBLE (-1600 3250);
FORCEPROP 1 LAST PATH I216
J 0
(-1600 3300);
DISPLAY 0.872340 (-1600 3300);
PAINT AQUA (-1600 3300);
DISPLAY INVISIBLE (-1600 3300);
FORCEPROP 2 LAST CDS_LIB mstr_symbols
J 0
(-1675 3300);
PAINT MONO (-1675 3300);
DISPLAY INVISIBLE (-1675 3300);
FORCEPROP 1 LAST VOLTAGE 0
J 0
(-1675 3300);
PAINT SKYBLUE (-1675 3300);
DISPLAY INVISIBLE (-1675 3300);
FORCEPROP 1 LAST HDL_POWER GND
J 0
(-1675 3450);
DISPLAY 0.872340 (-1675 3450);
PAINT GREEN (-1675 3450);
DISPLAY INVISIBLE (-1675 3450);
FORCEADD CAPP..1
(-1675 3525);
FORCEPROP 1 LASTPIN (-1675 3425) $PN 2
J 0
(-1665 3410);
DISPLAY 0.617021 (-1665 3410);
PAINT WHITE (-1665 3410);
FORCEPROP 1 LAST TOLERANCE 20%
J 0
(-1625 3525);
DISPLAY 0.617021 (-1625 3525);
PAINT SKYBLUE (-1625 3525);
FORCEPROP 1 LASTPIN (-1675 3625) $PN 1
J 0
(-1665 3610);
DISPLAY 0.617021 (-1665 3610);
PAINT WHITE (-1665 3610);
FORCEPROP 1 LAST MATERIAL POSCAP
J 0
(-1625 3425);
DISPLAY 0.617021 (-1625 3425);
PAINT SKYBLUE (-1625 3425);
FORCEPROP 1 LAST VOLTAGE 6.3V
J 0
(-1625 3475);
DISPLAY 0.617021 (-1625 3475);
PAINT SKYBLUE (-1625 3475);
FORCEPROP 1 LAST PACK_TYPE 7343LF
J 0
(-1625 3375);
DISPLAY 0.617021 (-1625 3375);
PAINT SKYBLUE (-1625 3375);
FORCEPROP 1 LAST VALUE 330UF
J 0
(-1625 3575);
DISPLAY 0.617021 (-1625 3575);
PAINT SKYBLUE (-1625 3575);
FORCEPROP 1 LAST PART_NUMBER 724613-042
J 0
(-1625 3325);
DISPLAY 0.617021 (-1625 3325);
PAINT BLUE (-1625 3325);
FORCEPROP 1 LAST LOCATION C4F7
J 0
(-1625 3625);
DISPLAY 0.617021 (-1625 3625);
PAINT AQUA (-1625 3625);
FORCEPROP 2 LAST ROOM PVPP_KLM_VR
J 0
(-1675 3525);
PAINT GREEN (-1675 3525);
DISPLAY INVISIBLE (-1675 3525);
FORCEPROP 2 LAST CDS_LIB mstr_discrete
J 0
(-1675 3525);
PAINT MONO (-1675 3525);
DISPLAY INVISIBLE (-1675 3525);
FORCEPROP 2 LAST BOM_COST PVPP_KLM_VR
J 0
(-1675 3525);
DISPLAY 0.659574 (-1675 3525);
PAINT WHITE (-1675 3525);
DISPLAY INVISIBLE (-1675 3525);
FORCEPROP 2 LAST REUSE_ID 28
J 0
(-1625 3725);
DISPLAY 1.042553 (-1625 3725);
PAINT ORANGE (-1625 3725);
DISPLAY INVISIBLE (-1625 3725);
FORCEPROP 2 LAST CDS_SEC 1
J 0
(-1625 3725);
DISPLAY 1.042553 (-1625 3725);
PAINT ORANGE (-1625 3725);
DISPLAY INVISIBLE (-1625 3725);
FORCEPROP 2 LAST $SEC 1
J 0
(-1625 3725);
DISPLAY 0.680851 (-1625 3725);
PAINT MONO (-1625 3725);
DISPLAY INVISIBLE (-1625 3725);
FORCEPROP 2 LAST CDS_LOCATION C4F7
J 0
(-1625 3625);
DISPLAY 0.617021 (-1625 3625);
PAINT AQUA (-1625 3625);
DISPLAY INVISIBLE (-1625 3625);
FORCEPROP 1 LAST PATH I217
J 0
(-1625 3675);
DISPLAY 0.978723 (-1625 3675);
PAINT ORANGE (-1625 3675);
DISPLAY INVISIBLE (-1625 3675);
FORCEADD GND..1
(-1075 3325);
FORCEPROP 3 LASTPIN (-1075 3375) SIG_NAME GND\g
J 0
(-1065 3385);
DISPLAY 0.659574 (-1065 3385);
PAINT MONO (-1065 3385);
DISPLAY INVISIBLE (-1065 3385);
FORCEPROP 2 LAST BOM_COST PVPP_KLM_VR
J 0
(-1925 3400);
DISPLAY 1.042553 (-1925 3400);
PAINT WHITE (-1925 3400);
DISPLAY INVISIBLE (-1925 3400);
FORCEPROP 2 LAST ROOM PVPP_KLM_VR
J 0
(-1650 3400);
DISPLAY 1.042553 (-1650 3400);
PAINT GREEN (-1650 3400);
DISPLAY INVISIBLE (-1650 3400);
FORCEPROP 1 LAST BODY_TYPE PLUMBING
J 0
(-1120 3282);
DISPLAY 0.340426 (-1120 3282);
PAINT GREEN (-1120 3282);
DISPLAY INVISIBLE (-1120 3282);
FORCEPROP 2 LAST CDS_LIB mstr_symbols
J 0
(-1075 3325);
PAINT MONO (-1075 3325);
DISPLAY INVISIBLE (-1075 3325);
FORCEPROP 1 LAST VOLTAGE 0
J 0
(-1075 3325);
PAINT SKYBLUE (-1075 3325);
DISPLAY INVISIBLE (-1075 3325);
FORCEPROP 1 LAST HDL_POWER GND
J 0
(-1075 3475);
DISPLAY 0.872340 (-1075 3475);
PAINT GREEN (-1075 3475);
DISPLAY INVISIBLE (-1075 3475);
FORCEPROP 1 LAST PATH I220
J 0
(-1000 3325);
DISPLAY 0.872340 (-1000 3325);
PAINT AQUA (-1000 3325);
DISPLAY INVISIBLE (-1000 3325);
FORCEPROP 1 LAST SIZE 1B
J 0
(-1000 3275);
DISPLAY 0.872340 (-1000 3275);
PAINT GREEN (-1000 3275);
DISPLAY INVISIBLE (-1000 3275);
FORCEADD CAP..1
(-1075 3525);
FORCEPROP 1 LASTPIN (-1075 3425) $PN 2
J 0
(-1065 3405);
DISPLAY 0.617021 (-1065 3405);
PAINT WHITE (-1065 3405);
FORCEPROP 1 LASTPIN (-1075 3625) $PN 1
J 0
(-1065 3605);
DISPLAY 0.617021 (-1065 3605);
PAINT WHITE (-1065 3605);
FORCEPROP 1 LAST MATERIAL X6S
J 0
(-1025 3425);
DISPLAY 0.617021 (-1025 3425);
PAINT SKYBLUE (-1025 3425);
FORCEPROP 1 LAST VOLTAGE 4V
J 0
(-1025 3525);
DISPLAY 0.617021 (-1025 3525);
PAINT SKYBLUE (-1025 3525);
FORCEPROP 1 LAST PACK_TYPE 0805
J 0
(-1025 3325);
DISPLAY 0.617021 (-1025 3325);
PAINT SKYBLUE (-1025 3325);
FORCEPROP 1 LAST TOLERANCE 20%
J 0
(-1025 3475);
DISPLAY 0.617021 (-1025 3475);
PAINT SKYBLUE (-1025 3475);
FORCEPROP 1 LAST VALUE 47UF
J 0
(-1025 3575);
DISPLAY 0.617021 (-1025 3575);
PAINT SKYBLUE (-1025 3575);
FORCEPROP 1 LAST PART_NUMBER C95333-006
J 0
(-1025 3375);
DISPLAY 0.617021 (-1025 3375);
PAINT BLUE (-1025 3375);
FORCEPROP 1 LAST LOCATION C6U3
J 0
(-1025 3625);
DISPLAY 0.617021 (-1025 3625);
PAINT AQUA (-1025 3625);
FORCEPROP 2 LAST BOM_COST PVPP_KLM_VR
J 0
(-1075 3525);
PAINT WHITE (-1075 3525);
DISPLAY INVISIBLE (-1075 3525);
FORCEPROP 2 LAST CDS_LIB mstr_discrete
J 0
(-1075 3525);
PAINT MONO (-1075 3525);
DISPLAY INVISIBLE (-1075 3525);
FORCEPROP 2 LAST ROOM PVPP_KLM_VR
J 0
(-1075 3525);
PAINT GREEN (-1075 3525);
DISPLAY INVISIBLE (-1075 3525);
FORCEPROP 2 LAST REUSE_ID 33
J 0
(-1025 3725);
DISPLAY 1.042553 (-1025 3725);
PAINT ORANGE (-1025 3725);
DISPLAY INVISIBLE (-1025 3725);
FORCEPROP 2 LAST CDS_SEC 1
J 0
(-1025 3725);
DISPLAY 1.042553 (-1025 3725);
PAINT ORANGE (-1025 3725);
DISPLAY INVISIBLE (-1025 3725);
FORCEPROP 2 LAST $SEC 1
J 0
(-1025 3725);
DISPLAY 0.680851 (-1025 3725);
PAINT MONO (-1025 3725);
DISPLAY INVISIBLE (-1025 3725);
FORCEPROP 2 LAST CDS_LOCATION C6U3
J 0
(-1025 3625);
DISPLAY 0.617021 (-1025 3625);
PAINT AQUA (-1025 3625);
DISPLAY INVISIBLE (-1025 3625);
FORCEPROP 1 LAST PATH I221
J 0
(-1025 3675);
DISPLAY 0.978723 (-1025 3675);
PAINT WHITE (-1025 3675);
DISPLAY INVISIBLE (-1025 3675);
FORCEADD GND..1
(-775 3350);
FORCEPROP 3 LASTPIN (-775 3400) SIG_NAME GND\g
J 0
(-765 3410);
DISPLAY 0.659574 (-765 3410);
PAINT MONO (-765 3410);
DISPLAY INVISIBLE (-765 3410);
FORCEPROP 2 LAST BOM_COST PVPP_KLM_VR
J 0
(-1625 3425);
DISPLAY 1.042553 (-1625 3425);
PAINT WHITE (-1625 3425);
DISPLAY INVISIBLE (-1625 3425);
FORCEPROP 2 LAST ROOM PVPP_KLM_VR
J 0
(-1350 3425);
DISPLAY 1.042553 (-1350 3425);
PAINT GREEN (-1350 3425);
DISPLAY INVISIBLE (-1350 3425);
FORCEPROP 1 LAST HDL_POWER GND
J 0
(-775 3500);
DISPLAY 0.872340 (-775 3500);
PAINT GREEN (-775 3500);
DISPLAY INVISIBLE (-775 3500);
FORCEPROP 1 LAST BODY_TYPE PLUMBING
J 0
(-820 3307);
DISPLAY 0.340426 (-820 3307);
PAINT GREEN (-820 3307);
DISPLAY INVISIBLE (-820 3307);
FORCEPROP 2 LAST CDS_LIB mstr_symbols
J 0
(-775 3350);
PAINT MONO (-775 3350);
DISPLAY INVISIBLE (-775 3350);
FORCEPROP 1 LAST VOLTAGE 0
J 0
(-775 3350);
PAINT SKYBLUE (-775 3350);
DISPLAY INVISIBLE (-775 3350);
FORCEPROP 1 LAST PATH I222
J 0
(-700 3350);
DISPLAY 0.872340 (-700 3350);
PAINT AQUA (-700 3350);
DISPLAY INVISIBLE (-700 3350);
FORCEPROP 1 LAST SIZE 1B
J 0
(-700 3300);
DISPLAY 0.872340 (-700 3300);
PAINT GREEN (-700 3300);
DISPLAY INVISIBLE (-700 3300);
FORCEADD CAP..1
(-775 3500);
FORCEPROP 1 LASTPIN (-775 3400) $PN 2
J 0
(-765 3380);
DISPLAY 0.617021 (-765 3380);
PAINT WHITE (-765 3380);
FORCEPROP 1 LAST MATERIAL X6S
J 0
(-725 3400);
DISPLAY 0.617021 (-725 3400);
PAINT SKYBLUE (-725 3400);
FORCEPROP 1 LAST VOLTAGE 4V
J 0
(-725 3500);
DISPLAY 0.617021 (-725 3500);
PAINT SKYBLUE (-725 3500);
FORCEPROP 1 LAST VALUE 47UF
J 0
(-725 3550);
DISPLAY 0.617021 (-725 3550);
PAINT SKYBLUE (-725 3550);
FORCEPROP 1 LAST TOLERANCE 20%
J 0
(-725 3450);
DISPLAY 0.617021 (-725 3450);
PAINT SKYBLUE (-725 3450);
FORCEPROP 1 LAST PACK_TYPE 0805
J 0
(-725 3300);
DISPLAY 0.617021 (-725 3300);
PAINT SKYBLUE (-725 3300);
FORCEPROP 1 LASTPIN (-775 3600) $PN 1
J 0
(-765 3580);
DISPLAY 0.617021 (-765 3580);
PAINT WHITE (-765 3580);
FORCEPROP 1 LAST LOCATION C6U2
J 0
(-725 3600);
DISPLAY 0.617021 (-725 3600);
PAINT AQUA (-725 3600);
FORCEPROP 1 LAST PART_NUMBER C95333-006
J 0
(-725 3350);
DISPLAY 0.617021 (-725 3350);
PAINT BLUE (-725 3350);
FORCEPROP 2 LAST BOM_COST PVPP_KLM_VR
J 0
(-775 3500);
PAINT WHITE (-775 3500);
DISPLAY INVISIBLE (-775 3500);
FORCEPROP 2 LAST CDS_LIB mstr_discrete
J 0
(-775 3500);
PAINT MONO (-775 3500);
DISPLAY INVISIBLE (-775 3500);
FORCEPROP 2 LAST ROOM PVPP_KLM_VR
J 0
(-775 3500);
PAINT GREEN (-775 3500);
DISPLAY INVISIBLE (-775 3500);
FORCEPROP 1 LAST PATH I223
J 0
(-725 3650);
DISPLAY 0.978723 (-725 3650);
PAINT WHITE (-725 3650);
DISPLAY INVISIBLE (-725 3650);
FORCEPROP 2 LAST CDS_LOCATION C6U2
J 0
(-725 3600);
DISPLAY 0.617021 (-725 3600);
PAINT AQUA (-725 3600);
DISPLAY INVISIBLE (-725 3600);
FORCEPROP 2 LAST $SEC 1
J 0
(-725 3700);
DISPLAY 0.680851 (-725 3700);
PAINT MONO (-725 3700);
DISPLAY INVISIBLE (-725 3700);
FORCEPROP 2 LAST CDS_SEC 1
J 0
(-725 3700);
DISPLAY 1.042553 (-725 3700);
PAINT ORANGE (-725 3700);
DISPLAY INVISIBLE (-725 3700);
FORCEPROP 2 LAST REUSE_ID 33
J 0
(-725 3700);
DISPLAY 1.042553 (-725 3700);
PAINT ORANGE (-725 3700);
DISPLAY INVISIBLE (-725 3700);
FORCEADD CAP..2
R 2
(-3300 4050);
FORCEPROP 1 LASTPIN (-3400 4050) $PN 2
J 2
(-3385 4065);
DISPLAY 0.617021 (-3385 4065);
PAINT WHITE (-3385 4065);
FORCEPROP 1 LAST PACK_TYPE 0603LF
J 1
(-3300 3850);
DISPLAY 0.617021 (-3300 3850);
PAINT SKYBLUE (-3300 3850);
FORCEPROP 1 LAST VOLTAGE 25V
J 2
(-3300 3950);
DISPLAY 0.617021 (-3300 3950);
PAINT SKYBLUE (-3300 3950);
FORCEPROP 1 LAST MATERIAL X7R
J 2
(-3300 3900);
DISPLAY 0.617021 (-3300 3900);
PAINT SKYBLUE (-3300 3900);
FORCEPROP 1 LAST VALUE 0.1UF
J 0
(-3300 3950);
DISPLAY 0.617021 (-3300 3950);
PAINT SKYBLUE (-3300 3950);
FORCEPROP 1 LAST TOLERANCE 10%
J 0
(-3300 3900);
DISPLAY 0.617021 (-3300 3900);
PAINT SKYBLUE (-3300 3900);
FORCEPROP 1 LASTPIN (-3200 4050) $PN 1
J 2
(-3190 4065);
DISPLAY 0.617021 (-3190 4065);
PAINT WHITE (-3190 4065);
FORCEPROP 1 LAST PART_NUMBER 602433-020
J 1
(-3300 4100);
DISPLAY 0.617021 (-3300 4100);
PAINT BLUE (-3300 4100);
FORCEPROP 1 LAST LOCATION C4G26
J 1
(-3300 4150);
DISPLAY 0.617021 (-3300 4150);
PAINT AQUA (-3300 4150);
FORCEPROP 2 LAST CDS_LIB mstr_discrete
J 0
(-3300 4050);
PAINT MONO (-3300 4050);
DISPLAY INVISIBLE (-3300 4050);
FORCEPROP 2 LAST ROOM PVPP_KLM_VR
J 2
(-3300 4175);
DISPLAY 0.765957 (-3300 4175);
PAINT GREEN (-3300 4175);
DISPLAY INVISIBLE (-3300 4175);
FORCEPROP 1 LAST PATH I224
J 2
(-3300 4250);
DISPLAY 0.978723 (-3300 4250);
PAINT WHITE (-3300 4250);
DISPLAY INVISIBLE (-3300 4250);
FORCEPROP 2 LAST $SEC 1
J 0
(-3300 4300);
DISPLAY 0.680851 (-3300 4300);
PAINT MONO (-3300 4300);
DISPLAY INVISIBLE (-3300 4300);
FORCEPROP 2 LAST CDS_SEC 1
J 0
(-3345 4260);
DISPLAY 1.042553 (-3345 4260);
PAINT ORANGE (-3345 4260);
DISPLAY INVISIBLE (-3345 4260);
FORCEPROP 2 LAST BOM_COST PVPP_KLM_VR
J 0
(-3345 4210);
DISPLAY 1.042553 (-3345 4210);
PAINT WHITE (-3345 4210);
DISPLAY INVISIBLE (-3345 4210);
FORCEPROP 0 LAST SPOF TRUE
J 0
(-3300 4250);
DISPLAY 1.021277 (-3300 4250);
PAINT ORANGE (-3300 4250);
DISPLAY INVISIBLE (-3300 4250);
FORCEPROP 2 LAST REUSE_ID 27
J 0
(-3300 4300);
DISPLAY 1.042553 (-3300 4300);
PAINT ORANGE (-3300 4300);
DISPLAY INVISIBLE (-3300 4300);
FORCEADD NCP3232L..1
(-3725 2725);
FORCEPROP 2 LASTPIN (-4225 1875) $PN 5
J 2
(-4235 1885);
DISPLAY 0.617021 (-4235 1885);
PAINT ORANGE (-4235 1885);
FORCEPROP 2 LASTPIN (-4225 2475) $PN 4
J 2
(-4235 2485);
DISPLAY 0.617021 (-4235 2485);
PAINT ORANGE (-4235 2485);
FORCEPROP 2 LASTPIN (-4225 2375) $PN 7
J 2
(-4235 2385);
DISPLAY 0.617021 (-4235 2385);
PAINT ORANGE (-4235 2385);
FORCEPROP 2 LASTPIN (-4225 2675) $PN 40
J 2
(-4235 2685);
DISPLAY 0.617021 (-4235 2685);
PAINT ORANGE (-4235 2685);
FORCEPROP 2 LASTPIN (-4225 2775) $PN 6
J 2
(-4235 2785);
DISPLAY 0.617021 (-4235 2785);
PAINT ORANGE (-4235 2785);
FORCEPROP 2 LASTPIN (-4225 2575) $PN 1
J 2
(-4235 2585);
DISPLAY 0.617021 (-4235 2585);
PAINT ORANGE (-4235 2585);
FORCEPROP 2 LASTPIN (-4225 2875) $PN 38
J 2
(-4235 2885);
DISPLAY 0.617021 (-4235 2885);
PAINT ORANGE (-4235 2885);
FORCEPROP 2 LASTPIN (-4225 2975) $PN 8
J 2
(-4235 2985);
DISPLAY 0.617021 (-4235 2985);
PAINT ORANGE (-4235 2985);
FORCEPROP 2 LASTPIN (-4225 3025) $PN 9
J 2
(-4235 3035);
DISPLAY 0.617021 (-4235 3035);
PAINT ORANGE (-4235 3035);
FORCEPROP 2 LASTPIN (-4225 3075) $PN 10
J 2
(-4235 3085);
DISPLAY 0.617021 (-4235 3085);
PAINT ORANGE (-4235 3085);
FORCEPROP 2 LASTPIN (-4225 3125) $PN 11
J 2
(-4235 3135);
DISPLAY 0.617021 (-4235 3135);
PAINT ORANGE (-4235 3135);
FORCEPROP 2 LASTPIN (-4225 3175) $PN 12
J 2
(-4235 3185);
DISPLAY 0.617021 (-4235 3185);
PAINT ORANGE (-4235 3185);
FORCEPROP 2 LASTPIN (-4225 3225) $PN 13
J 2
(-4235 3235);
DISPLAY 0.617021 (-4235 3235);
PAINT ORANGE (-4235 3235);
FORCEPROP 2 LASTPIN (-4225 3275) $PN 14
J 2
(-4235 3285);
DISPLAY 0.617021 (-4235 3285);
PAINT ORANGE (-4235 3285);
FORCEPROP 2 LASTPIN (-4225 3425) $PN 39
J 2
(-4235 3435);
DISPLAY 0.617021 (-4235 3435);
PAINT ORANGE (-4235 3435);
FORCEPROP 2 LASTPIN (-4225 3325) $PN 42
J 2
(-4235 3335);
DISPLAY 0.617021 (-4235 3335);
PAINT ORANGE (-4235 3335);
FORCEPROP 1 LAST MATERIAL IC
J 0
(-4175 3625);
DISPLAY 0.617021 (-4175 3625);
PAINT SKYBLUE (-4175 3625);
FORCEPROP 1 LAST PART_NUMBER H86355-001
J 0
(-4175 1725);
DISPLAY 0.617021 (-4175 1725);
PAINT BLUE (-4175 1725);
FORCEPROP 1 LAST LOCATION EU4G1
J 0
(-4175 3675);
DISPLAY 0.617021 (-4175 3675);
PAINT AQUA (-4175 3675);
FORCEPROP 2 LASTPIN (-3225 1875) $PN 41
J 0
(-3215 1885);
DISPLAY 0.617021 (-3215 1885);
PAINT ORANGE (-3215 1885);
FORCEPROP 2 LASTPIN (-3225 1925) $PN 16
J 0
(-3215 1935);
DISPLAY 0.617021 (-3215 1935);
PAINT ORANGE (-3215 1935);
FORCEPROP 2 LASTPIN (-3225 1975) $PN 17
J 0
(-3215 1985);
DISPLAY 0.617021 (-3215 1985);
PAINT ORANGE (-3215 1985);
FORCEPROP 2 LASTPIN (-3225 2025) $PN 18
J 0
(-3215 2035);
DISPLAY 0.617021 (-3215 2035);
PAINT ORANGE (-3215 2035);
FORCEPROP 2 LASTPIN (-3225 2225) $PN 22
J 0
(-3215 2235);
DISPLAY 0.617021 (-3215 2235);
PAINT ORANGE (-3215 2235);
FORCEPROP 2 LASTPIN (-3225 2175) $PN 21
J 0
(-3215 2185);
DISPLAY 0.617021 (-3215 2185);
PAINT ORANGE (-3215 2185);
FORCEPROP 2 LASTPIN (-3225 2125) $PN 20
J 0
(-3215 2135);
DISPLAY 0.617021 (-3215 2135);
PAINT ORANGE (-3215 2135);
FORCEPROP 2 LASTPIN (-3225 2075) $PN 19
J 0
(-3215 2085);
DISPLAY 0.617021 (-3215 2085);
PAINT ORANGE (-3215 2085);
FORCEPROP 2 LASTPIN (-3225 2275) $PN 23
J 0
(-3215 2285);
DISPLAY 0.617021 (-3215 2285);
PAINT ORANGE (-3215 2285);
FORCEPROP 2 LASTPIN (-3225 2475) $PN 27
J 0
(-3215 2485);
DISPLAY 0.617021 (-3215 2485);
PAINT ORANGE (-3215 2485);
FORCEPROP 2 LASTPIN (-3225 2425) $PN 26
J 0
(-3215 2435);
DISPLAY 0.617021 (-3215 2435);
PAINT ORANGE (-3215 2435);
FORCEPROP 2 LASTPIN (-3225 2375) $PN 25
J 0
(-3215 2385);
DISPLAY 0.617021 (-3215 2385);
PAINT ORANGE (-3215 2385);
FORCEPROP 2 LASTPIN (-3225 2325) $PN 24
J 0
(-3215 2335);
DISPLAY 0.617021 (-3215 2335);
PAINT ORANGE (-3215 2335);
FORCEPROP 2 LASTPIN (-3225 2525) $PN 28
J 0
(-3215 2535);
DISPLAY 0.617021 (-3215 2535);
PAINT ORANGE (-3215 2535);
FORCEPROP 2 LASTPIN (-3225 2675) $PN 3
J 0
(-3215 2685);
DISPLAY 0.617021 (-3215 2685);
PAINT ORANGE (-3215 2685);
FORCEPROP 2 LASTPIN (-3225 2775) $PN 2
J 0
(-3215 2785);
DISPLAY 0.617021 (-3215 2785);
PAINT ORANGE (-3215 2785);
FORCEPROP 2 LASTPIN (-3225 2575) $PN 37
J 0
(-3215 2585);
DISPLAY 0.617021 (-3215 2585);
PAINT ORANGE (-3215 2585);
FORCEPROP 2 LASTPIN (-3225 2875) $PN 35
J 0
(-3215 2885);
DISPLAY 0.617021 (-3215 2885);
PAINT ORANGE (-3215 2885);
FORCEPROP 2 LASTPIN (-3225 2975) $PN 15
J 0
(-3215 2985);
DISPLAY 0.617021 (-3215 2985);
PAINT ORANGE (-3215 2985);
FORCEPROP 2 LASTPIN (-3225 3025) $PN 29
J 0
(-3215 3035);
DISPLAY 0.617021 (-3215 3035);
PAINT ORANGE (-3215 3035);
FORCEPROP 2 LASTPIN (-3225 3275) $PN 34
J 0
(-3215 3285);
DISPLAY 0.617021 (-3215 3285);
PAINT ORANGE (-3215 3285);
FORCEPROP 2 LASTPIN (-3225 3225) $PN 33
J 0
(-3215 3235);
DISPLAY 0.617021 (-3215 3235);
PAINT ORANGE (-3215 3235);
FORCEPROP 2 LASTPIN (-3225 3175) $PN 32
J 0
(-3215 3185);
DISPLAY 0.617021 (-3215 3185);
PAINT ORANGE (-3215 3185);
FORCEPROP 2 LASTPIN (-3225 3125) $PN 31
J 0
(-3215 3135);
DISPLAY 0.617021 (-3215 3135);
PAINT ORANGE (-3215 3135);
FORCEPROP 2 LASTPIN (-3225 3075) $PN 30
J 0
(-3215 3085);
DISPLAY 0.617021 (-3215 3085);
PAINT ORANGE (-3215 3085);
FORCEPROP 2 LASTPIN (-3225 3425) $PN 36
J 0
(-3215 3435);
DISPLAY 0.617021 (-3215 3435);
PAINT ORANGE (-3215 3435);
FORCEPROP 2 LASTPIN (-3225 3325) $PN 43
J 0
(-3215 3335);
DISPLAY 0.617021 (-3215 3335);
PAINT ORANGE (-3215 3335);
FORCEPROP 2 LAST CDS_LOCATION EU4G1
J 0
(-4175 3675);
DISPLAY 0.617021 (-4175 3675);
PAINT AQUA (-4175 3675);
DISPLAY INVISIBLE (-4175 3675);
FORCEPROP 2 LAST SEC 1
J 0
(-4175 3725);
DISPLAY 0.680851 (-4175 3725);
PAINT MONO (-4175 3725);
DISPLAY INVISIBLE (-4175 3725);
FORCEPROP 2 LAST SEC_TYPE SM
J 0
(-4175 3725);
DISPLAY 1.021277 (-4175 3725);
PAINT ORANGE (-4175 3725);
DISPLAY INVISIBLE (-4175 3725);
FORCEPROP 1 LAST PACK_TYPE SM
J 0
(-4175 3725);
PAINT SKYBLUE (-4175 3725);
DISPLAY INVISIBLE (-4175 3725);
FORCEPROP 1 LAST CDS_LMAN_SYM_OUTLINE -450,850,450,-900
J 0
(-3725 2725);
DISPLAY 0.468085 (-3725 2725);
PAINT GREEN (-3725 2725);
DISPLAY INVISIBLE (-3725 2725);
FORCEPROP 2 LAST CDS_LIB mstr_vreg
J 0
(-3725 2725);
PAINT ORANGE (-3725 2725);
DISPLAY INVISIBLE (-3725 2725);
FORCEPROP 1 LAST PATH I225
J 0
(-3675 3625);
PAINT GREEN (-3675 3625);
DISPLAY INVISIBLE (-3675 3625);
FORCEADD AGND_SCSI..1
(-6500 1800);
FORCEPROP 3 LASTPIN (-6500 1850) SIG_NAME AGND_PVPP_GHJ\g
J 0
(-6490 1860);
DISPLAY 0.659574 (-6490 1860);
PAINT MONO (-6490 1860);
DISPLAY INVISIBLE (-6490 1860);
FORCEPROP 1 LAST HDL_POWER AGND_PVPP_GHJ
J 1
(-6475 1725);
DISPLAY 0.617021 (-6475 1725);
PAINT GREEN (-6475 1725);
FORCEPROP 1 LAST VOLTAGE 0.0V
J 0
(-6545 1757);
DISPLAY 0.340426 (-6545 1757);
PAINT SKYBLUE (-6545 1757);
DISPLAY INVISIBLE (-6545 1757);
FORCEPROP 2 LAST BOM_COST PVPP_KLM_VR
J 0
(-6650 1750);
DISPLAY 1.042553 (-6650 1750);
PAINT WHITE (-6650 1750);
DISPLAY INVISIBLE (-6650 1750);
FORCEPROP 2 LAST CDS_LIB mstr_symbols
J 0
(-6500 1800);
PAINT MONO (-6500 1800);
DISPLAY INVISIBLE (-6500 1800);
FORCEPROP 1 LAST BODY_TYPE PLUMBING
J 0
(-6545 1757);
DISPLAY 0.340426 (-6545 1757);
PAINT GREEN (-6545 1757);
DISPLAY INVISIBLE (-6545 1757);
FORCEPROP 1 LAST PATH I226
J 0
(-6425 1800);
DISPLAY 0.872340 (-6425 1800);
PAINT AQUA (-6425 1800);
DISPLAY INVISIBLE (-6425 1800);
FORCEPROP 2 LAST ROOM PVPP_KLM_VR
J 0
(-6650 1750);
DISPLAY 1.042553 (-6650 1750);
PAINT GREEN (-6650 1750);
DISPLAY INVISIBLE (-6650 1750);
FORCEADD AGND_SCSI..1
(-5525 1950);
FORCEPROP 3 LASTPIN (-5525 2000) SIG_NAME AGND_PVPP_GHJ\g
J 0
(-5515 2010);
DISPLAY 0.659574 (-5515 2010);
PAINT MONO (-5515 2010);
DISPLAY INVISIBLE (-5515 2010);
FORCEPROP 1 LAST HDL_POWER AGND_PVPP_GHJ
J 1
(-5500 1875);
DISPLAY 0.617021 (-5500 1875);
PAINT GREEN (-5500 1875);
FORCEPROP 2 LAST BOM_COST PVPP_KLM_VR
J 0
(-5675 1900);
DISPLAY 1.042553 (-5675 1900);
PAINT WHITE (-5675 1900);
DISPLAY INVISIBLE (-5675 1900);
FORCEPROP 2 LAST ROOM PVPP_KLM_VR
J 0
(-5675 1900);
DISPLAY 1.042553 (-5675 1900);
PAINT GREEN (-5675 1900);
DISPLAY INVISIBLE (-5675 1900);
FORCEPROP 1 LAST VOLTAGE 0.0V
J 0
(-5570 1907);
DISPLAY 0.340426 (-5570 1907);
PAINT SKYBLUE (-5570 1907);
DISPLAY INVISIBLE (-5570 1907);
FORCEPROP 2 LAST CDS_LIB mstr_symbols
J 0
(-5525 1950);
PAINT MONO (-5525 1950);
DISPLAY INVISIBLE (-5525 1950);
FORCEPROP 1 LAST BODY_TYPE PLUMBING
J 0
(-5570 1907);
DISPLAY 0.340426 (-5570 1907);
PAINT GREEN (-5570 1907);
DISPLAY INVISIBLE (-5570 1907);
FORCEPROP 1 LAST PATH I227
J 0
(-5450 1950);
DISPLAY 0.872340 (-5450 1950);
PAINT AQUA (-5450 1950);
DISPLAY INVISIBLE (-5450 1950);
FORCEADD AGND_SCSI..1
(-5000 1800);
FORCEPROP 3 LASTPIN (-5000 1850) SIG_NAME AGND_PVPP_GHJ\g
J 0
(-4990 1860);
DISPLAY 0.659574 (-4990 1860);
PAINT MONO (-4990 1860);
DISPLAY INVISIBLE (-4990 1860);
FORCEPROP 1 LAST HDL_POWER AGND_PVPP_GHJ
J 1
(-4975 1725);
DISPLAY 0.617021 (-4975 1725);
PAINT GREEN (-4975 1725);
FORCEPROP 2 LAST BOM_COST PVPP_KLM_VR
J 0
(-5150 1750);
DISPLAY 1.042553 (-5150 1750);
PAINT WHITE (-5150 1750);
DISPLAY INVISIBLE (-5150 1750);
FORCEPROP 2 LAST ROOM PVPP_KLM_VR
J 0
(-5150 1750);
DISPLAY 1.042553 (-5150 1750);
PAINT GREEN (-5150 1750);
DISPLAY INVISIBLE (-5150 1750);
FORCEPROP 1 LAST BODY_TYPE PLUMBING
J 0
(-5045 1757);
DISPLAY 0.340426 (-5045 1757);
PAINT GREEN (-5045 1757);
DISPLAY INVISIBLE (-5045 1757);
FORCEPROP 1 LAST VOLTAGE 0.0V
J 0
(-5045 1757);
DISPLAY 0.340426 (-5045 1757);
PAINT SKYBLUE (-5045 1757);
DISPLAY INVISIBLE (-5045 1757);
FORCEPROP 2 LAST CDS_LIB mstr_symbols
J 0
(-5000 1800);
PAINT MONO (-5000 1800);
DISPLAY INVISIBLE (-5000 1800);
FORCEPROP 1 LAST PATH I228
J 0
(-4925 1800);
DISPLAY 0.872340 (-4925 1800);
PAINT AQUA (-4925 1800);
DISPLAY INVISIBLE (-4925 1800);
FORCEADD AGND_SCSI..1
(-4675 1200);
FORCEPROP 3 LASTPIN (-4675 1250) SIG_NAME AGND_PVPP_GHJ\g
J 0
(-4665 1260);
DISPLAY 0.659574 (-4665 1260);
PAINT MONO (-4665 1260);
DISPLAY INVISIBLE (-4665 1260);
FORCEPROP 1 LAST HDL_POWER AGND_PVPP_GHJ
J 1
(-4650 1125);
DISPLAY 0.617021 (-4650 1125);
PAINT GREEN (-4650 1125);
FORCEPROP 1 LAST BODY_TYPE PLUMBING
J 0
(-4720 1157);
DISPLAY 0.340426 (-4720 1157);
PAINT GREEN (-4720 1157);
DISPLAY INVISIBLE (-4720 1157);
FORCEPROP 2 LAST CDS_LIB mstr_symbols
J 0
(-4675 1200);
PAINT MONO (-4675 1200);
DISPLAY INVISIBLE (-4675 1200);
FORCEPROP 1 LAST VOLTAGE 0
J 0
(-4650 1225);
DISPLAY 1.021277 (-4650 1225);
PAINT SKYBLUE (-4650 1225);
DISPLAY INVISIBLE (-4650 1225);
FORCEPROP 1 LAST PATH I229
J 0
(-4600 1200);
DISPLAY 0.872340 (-4600 1200);
PAINT AQUA (-4600 1200);
DISPLAY INVISIBLE (-4600 1200);
FORCEADD AGND_SCSI..1
(-4300 1700);
FORCEPROP 3 LASTPIN (-4300 1750) SIG_NAME AGND_PVPP_GHJ\g
J 0
(-4290 1760);
DISPLAY 0.659574 (-4290 1760);
PAINT MONO (-4290 1760);
DISPLAY INVISIBLE (-4290 1760);
FORCEPROP 1 LAST HDL_POWER AGND_PVPP_GHJ
J 1
(-4275 1625);
DISPLAY 0.617021 (-4275 1625);
PAINT GREEN (-4275 1625);
FORCEPROP 2 LAST BOM_COST PVPP_KLM_VR
J 0
(-4450 1650);
DISPLAY 1.042553 (-4450 1650);
PAINT WHITE (-4450 1650);
DISPLAY INVISIBLE (-4450 1650);
FORCEPROP 2 LAST ROOM PVPP_KLM_VR
J 0
(-4450 1650);
DISPLAY 1.042553 (-4450 1650);
PAINT GREEN (-4450 1650);
DISPLAY INVISIBLE (-4450 1650);
FORCEPROP 1 LAST PATH I230
J 0
(-4225 1700);
DISPLAY 0.872340 (-4225 1700);
PAINT AQUA (-4225 1700);
DISPLAY INVISIBLE (-4225 1700);
FORCEPROP 1 LAST BODY_TYPE PLUMBING
J 0
(-4345 1657);
DISPLAY 0.340426 (-4345 1657);
PAINT GREEN (-4345 1657);
DISPLAY INVISIBLE (-4345 1657);
FORCEPROP 2 LAST CDS_LIB mstr_symbols
J 0
(-4300 1700);
PAINT MONO (-4300 1700);
DISPLAY INVISIBLE (-4300 1700);
FORCEPROP 1 LAST VOLTAGE 0.0V
J 0
(-4345 1657);
DISPLAY 0.340426 (-4345 1657);
PAINT SKYBLUE (-4345 1657);
DISPLAY INVISIBLE (-4345 1657);
FORCEADD CAP_A..1
(-5050 3325);
FORCEPROP 1 LASTPIN (-5050 3225) $PN 2
J 0
(-5040 3205);
DISPLAY 0.617021 (-5040 3205);
PAINT ORANGE (-5040 3205);
FORCEPROP 1 LAST MATERIAL X7R
J 0
(-5000 3225);
DISPLAY 0.617021 (-5000 3225);
PAINT SKYBLUE (-5000 3225);
FORCEPROP 1 LAST TOLERANCE 10%
J 0
(-5000 3275);
DISPLAY 0.617021 (-5000 3275);
PAINT SKYBLUE (-5000 3275);
FORCEPROP 1 LAST VOLTAGE 16V
J 0
(-5000 3325);
DISPLAY 0.617021 (-5000 3325);
PAINT SKYBLUE (-5000 3325);
FORCEPROP 1 LASTPIN (-5050 3425) $PN 1
J 0
(-5040 3405);
DISPLAY 0.617021 (-5040 3405);
PAINT ORANGE (-5040 3405);
FORCEPROP 1 LAST LOCATION C6U5
J 0
(-5000 3425);
DISPLAY 0.617021 (-5000 3425);
PAINT AQUA (-5000 3425);
FORCEPROP 1 LAST PACK_TYPE 0402V
J 0
(-5000 3125);
DISPLAY 0.617021 (-5000 3125);
PAINT SKYBLUE (-5000 3125);
FORCEPROP 1 LAST VALUE 0.1UF
J 0
(-5000 3375);
DISPLAY 0.617021 (-5000 3375);
PAINT SKYBLUE (-5000 3375);
FORCEPROP 1 LAST PART_NUMBER A36096-030
J 0
(-5000 3175);
DISPLAY 0.617021 (-5000 3175);
PAINT BLUE (-5000 3175);
FORCEPROP 2 LAST CDS_LIB dev_discrete
J 0
(-5050 3325);
PAINT ORANGE (-5050 3325);
DISPLAY INVISIBLE (-5050 3325);
FORCEPROP 2 LAST SEC 1
J 0
(-5000 3525);
PAINT MONO (-5000 3525);
DISPLAY INVISIBLE (-5000 3525);
FORCEPROP 2 LAST SEC_TYPE 0402V
J 0
(-5000 3525);
DISPLAY 1.021277 (-5000 3525);
PAINT ORANGE (-5000 3525);
DISPLAY INVISIBLE (-5000 3525);
FORCEPROP 2 LAST CDS_SEC 1
J 0
(-5000 3475);
PAINT ORANGE (-5000 3475);
DISPLAY INVISIBLE (-5000 3475);
FORCEPROP 2 LAST CDS_LOCATION C6U5
J 0
(-5000 3425);
DISPLAY 0.617021 (-5000 3425);
PAINT AQUA (-5000 3425);
DISPLAY INVISIBLE (-5000 3425);
FORCEPROP 1 LAST PATH I242
J 0
(-5000 3475);
DISPLAY 0.978723 (-5000 3475);
PAINT WHITE (-5000 3475);
DISPLAY INVISIBLE (-5000 3475);
FORCEADD GND..1
(-5050 3100);
FORCEPROP 3 LASTPIN (-5050 3150) SIG_NAME GND\g
J 0
(-5040 3160);
DISPLAY 0.659574 (-5040 3160);
PAINT MONO (-5040 3160);
DISPLAY INVISIBLE (-5040 3160);
FORCEPROP 2 LAST BOM_COST PVPP_KLM_VR
J 0
(-5900 3175);
DISPLAY 1.042553 (-5900 3175);
PAINT WHITE (-5900 3175);
DISPLAY INVISIBLE (-5900 3175);
FORCEPROP 2 LAST ROOM PVPP_KLM_VR
J 0
(-5625 3175);
DISPLAY 1.042553 (-5625 3175);
PAINT GREEN (-5625 3175);
DISPLAY INVISIBLE (-5625 3175);
FORCEPROP 1 LAST BODY_TYPE PLUMBING
J 0
(-5095 3057);
DISPLAY 0.340426 (-5095 3057);
PAINT GREEN (-5095 3057);
DISPLAY INVISIBLE (-5095 3057);
FORCEPROP 1 LAST SIZE 1B
J 0
(-4975 3050);
DISPLAY 0.872340 (-4975 3050);
PAINT GREEN (-4975 3050);
DISPLAY INVISIBLE (-4975 3050);
FORCEPROP 2 LAST CDS_LIB mstr_symbols
J 0
(-5050 3100);
PAINT MONO (-5050 3100);
DISPLAY INVISIBLE (-5050 3100);
FORCEPROP 1 LAST VOLTAGE 0
J 0
(-5050 3100);
PAINT SKYBLUE (-5050 3100);
DISPLAY INVISIBLE (-5050 3100);
FORCEPROP 1 LAST HDL_POWER GND
J 0
(-5050 3250);
DISPLAY 0.872340 (-5050 3250);
PAINT GREEN (-5050 3250);
DISPLAY INVISIBLE (-5050 3250);
FORCEPROP 1 LAST PATH I243
J 0
(-4975 3100);
DISPLAY 0.872340 (-4975 3100);
PAINT AQUA (-4975 3100);
DISPLAY INVISIBLE (-4975 3100);
FORCEADD AGND_SCSI..1
(-5300 2575);
FORCEPROP 3 LASTPIN (-5300 2625) SIG_NAME AGND_PVPP_GHJ\g
J 0
(-5290 2635);
DISPLAY 0.659574 (-5290 2635);
PAINT MONO (-5290 2635);
DISPLAY INVISIBLE (-5290 2635);
FORCEPROP 1 LAST HDL_POWER AGND_PVPP_GHJ
J 1
(-5275 2500);
DISPLAY 0.617021 (-5275 2500);
PAINT GREEN (-5275 2500);
FORCEPROP 1 LAST VOLTAGE 0.0V
J 0
(-5345 2532);
DISPLAY 0.340426 (-5345 2532);
PAINT SKYBLUE (-5345 2532);
DISPLAY INVISIBLE (-5345 2532);
FORCEPROP 1 LAST BODY_TYPE PLUMBING
J 0
(-5345 2532);
DISPLAY 0.340426 (-5345 2532);
PAINT GREEN (-5345 2532);
DISPLAY INVISIBLE (-5345 2532);
FORCEPROP 2 LAST ROOM PVPP_KLM_VR
J 0
(-5450 2525);
DISPLAY 1.042553 (-5450 2525);
PAINT GREEN (-5450 2525);
DISPLAY INVISIBLE (-5450 2525);
FORCEPROP 2 LAST BOM_COST PVPP_KLM_VR
J 0
(-5450 2525);
DISPLAY 1.042553 (-5450 2525);
PAINT WHITE (-5450 2525);
DISPLAY INVISIBLE (-5450 2525);
FORCEPROP 1 LAST PATH I244
J 0
(-5225 2575);
DISPLAY 0.872340 (-5225 2575);
PAINT AQUA (-5225 2575);
DISPLAY INVISIBLE (-5225 2575);
FORCEPROP 2 LAST CDS_LIB mstr_symbols
J 0
(-5300 2575);
PAINT MONO (-5300 2575);
DISPLAY INVISIBLE (-5300 2575);
FORCEADD GND..1
(-1375 3325);
FORCEPROP 3 LASTPIN (-1375 3375) SIG_NAME GND\g
J 0
(-1365 3385);
DISPLAY 0.659574 (-1365 3385);
PAINT MONO (-1365 3385);
DISPLAY INVISIBLE (-1365 3385);
FORCEPROP 2 LAST BOM_COST PVPP_KLM_VR
J 0
(-2225 3400);
DISPLAY 1.042553 (-2225 3400);
PAINT WHITE (-2225 3400);
DISPLAY INVISIBLE (-2225 3400);
FORCEPROP 2 LAST ROOM PVPP_KLM_VR
J 0
(-1950 3400);
DISPLAY 1.042553 (-1950 3400);
PAINT GREEN (-1950 3400);
DISPLAY INVISIBLE (-1950 3400);
FORCEPROP 1 LAST BODY_TYPE PLUMBING
J 0
(-1420 3282);
DISPLAY 0.340426 (-1420 3282);
PAINT GREEN (-1420 3282);
DISPLAY INVISIBLE (-1420 3282);
FORCEPROP 1 LAST SIZE 1B
J 0
(-1300 3275);
DISPLAY 0.872340 (-1300 3275);
PAINT GREEN (-1300 3275);
DISPLAY INVISIBLE (-1300 3275);
FORCEPROP 1 LAST PATH I246
J 0
(-1300 3325);
DISPLAY 0.872340 (-1300 3325);
PAINT AQUA (-1300 3325);
DISPLAY INVISIBLE (-1300 3325);
FORCEPROP 2 LAST CDS_LIB mstr_symbols
J 0
(-1375 3325);
PAINT MONO (-1375 3325);
DISPLAY INVISIBLE (-1375 3325);
FORCEPROP 1 LAST VOLTAGE 0
J 0
(-1375 3325);
PAINT SKYBLUE (-1375 3325);
DISPLAY INVISIBLE (-1375 3325);
FORCEPROP 1 LAST HDL_POWER GND
J 0
(-1375 3475);
DISPLAY 0.872340 (-1375 3475);
PAINT GREEN (-1375 3475);
DISPLAY INVISIBLE (-1375 3475);
FORCEADD RES..1
(-3375 825);
FORCEPROP 1 LAST VALUE 22.1
J 2
(-3400 725);
DISPLAY 0.617021 (-3400 725);
PAINT SKYBLUE (-3400 725);
FORCEPROP 1 LAST WATTAGE 1/16W
J 2
(-3400 675);
DISPLAY 0.617021 (-3400 675);
PAINT SKYBLUE (-3400 675);
FORCEPROP 1 LASTPIN (-3475 825) $PN 1
J 0
(-3463 837);
DISPLAY 0.617021 (-3463 837);
PAINT ORANGE (-3463 837);
FORCEPROP 1 LAST MATERIAL CHIP
J 0
(-3375 675);
DISPLAY 0.617021 (-3375 675);
PAINT SKYBLUE (-3375 675);
FORCEPROP 1 LAST TOLERANCE 1.0%
J 0
(-3375 725);
DISPLAY 0.617021 (-3375 725);
PAINT SKYBLUE (-3375 725);
FORCEPROP 1 LAST PART_NUMBER G21796-250
J 0
(-3425 925);
DISPLAY 0.617021 (-3425 925);
PAINT BLUE (-3425 925);
FORCEPROP 1 LAST LOCATION R4G12
J 0
(-3425 875);
DISPLAY 0.617021 (-3425 875);
PAINT AQUA (-3425 875);
FORCEPROP 1 LASTPIN (-3275 825) $PN 2
J 0
(-3313 837);
DISPLAY 0.617021 (-3313 837);
PAINT ORANGE (-3313 837);
FORCEPROP 1 LAST PACK_TYPE 0402
J 0
(-3125 675);
DISPLAY 0.617021 (-3125 675);
PAINT SKYBLUE (-3125 675);
FORCEPROP 2 LAST CDS_LIB mstr_discrete
J 0
(-3375 825);
PAINT MONO (-3375 825);
DISPLAY INVISIBLE (-3375 825);
FORCEPROP 2 LAST CDS_LOCATION R4G12
J 0
(-3425 875);
DISPLAY 0.617021 (-3425 875);
PAINT AQUA (-3425 875);
DISPLAY INVISIBLE (-3425 875);
FORCEPROP 1 LAST PATH I247
J 0
(-3425 975);
DISPLAY 0.978723 (-3425 975);
PAINT WHITE (-3425 975);
DISPLAY INVISIBLE (-3425 975);
FORCEPROP 2 LAST ROOM PVPP_GHJ_VR
J 0
(-3425 925);
DISPLAY 1.361702 (-3425 925);
PAINT ORANGE (-3425 925);
DISPLAY INVISIBLE (-3425 925);
FORCEPROP 2 LAST SEC 1
J 0
(-3425 1025);
DISPLAY 0.680851 (-3425 1025);
PAINT MONO (-3425 1025);
DISPLAY INVISIBLE (-3425 1025);
FORCEPROP 2 LAST SEC_TYPE 0402
J 0
(-3425 1025);
DISPLAY 1.021277 (-3425 1025);
PAINT ORANGE (-3425 1025);
DISPLAY INVISIBLE (-3425 1025);
FORCEADD CAP..1
(-6700 3975);
FORCEPROP 1 LASTPIN (-6700 4075) $PN 1
J 0
(-6690 4055);
DISPLAY 0.617021 (-6690 4055);
PAINT ORANGE (-6690 4055);
FORCEPROP 1 LASTPIN (-6700 3875) $PN 2
J 0
(-6690 3855);
DISPLAY 0.617021 (-6690 3855);
PAINT ORANGE (-6690 3855);
FORCEPROP 1 LAST MATERIAL X6S
J 0
(-6650 3875);
DISPLAY 0.617021 (-6650 3875);
PAINT SKYBLUE (-6650 3875);
FORCEPROP 1 LAST VOLTAGE 16V
J 0
(-6650 3975);
DISPLAY 0.617021 (-6650 3975);
PAINT SKYBLUE (-6650 3975);
FORCEPROP 1 LAST PACK_TYPE 0805
J 0
(-6650 3775);
DISPLAY 0.617021 (-6650 3775);
PAINT SKYBLUE (-6650 3775);
FORCEPROP 1 LAST TOLERANCE 10%
J 0
(-6650 3925);
DISPLAY 0.617021 (-6650 3925);
PAINT SKYBLUE (-6650 3925);
FORCEPROP 1 LAST VALUE 10UF
J 0
(-6650 4025);
DISPLAY 0.617021 (-6650 4025);
PAINT SKYBLUE (-6650 4025);
FORCEPROP 1 LAST PART_NUMBER C95333-007
J 0
(-6650 3825);
DISPLAY 0.617021 (-6650 3825);
PAINT BLUE (-6650 3825);
FORCEPROP 1 LAST LOCATION C6U4
J 0
(-6650 4075);
DISPLAY 0.617021 (-6650 4075);
PAINT AQUA (-6650 4075);
FORCEPROP 2 LAST CDS_LIB mstr_discrete
J 0
(-6700 3975);
PAINT MONO (-6700 3975);
DISPLAY INVISIBLE (-6700 3975);
FORCEPROP 2 LAST CDS_LOCATION C6U4
J 0
(-6650 4075);
DISPLAY 0.617021 (-6650 4075);
PAINT AQUA (-6650 4075);
DISPLAY INVISIBLE (-6650 4075);
FORCEPROP 1 LAST PATH I248
J 0
(-6650 4125);
DISPLAY 0.978723 (-6650 4125);
PAINT WHITE (-6650 4125);
DISPLAY INVISIBLE (-6650 4125);
FORCEPROP 2 LAST SEC 1
J 0
(-6650 4175);
DISPLAY 0.680851 (-6650 4175);
PAINT MONO (-6650 4175);
DISPLAY INVISIBLE (-6650 4175);
FORCEPROP 2 LAST SEC_TYPE 0805
J 0
(-6650 4175);
DISPLAY 1.021277 (-6650 4175);
PAINT ORANGE (-6650 4175);
DISPLAY INVISIBLE (-6650 4175);
FORCEADD GND..1
(-6700 3775);
FORCEPROP 3 LASTPIN (-6700 3825) SIG_NAME GND\g
J 0
(-6690 3835);
DISPLAY 0.659574 (-6690 3835);
PAINT MONO (-6690 3835);
DISPLAY INVISIBLE (-6690 3835);
FORCEPROP 2 LAST ROOM PVPP_KLM_VR
J 0
(-7275 3850);
DISPLAY 1.042553 (-7275 3850);
PAINT GREEN (-7275 3850);
DISPLAY INVISIBLE (-7275 3850);
FORCEPROP 2 LAST BOM_COST PVPP_KLM_VR
J 0
(-7550 3850);
DISPLAY 1.042553 (-7550 3850);
PAINT WHITE (-7550 3850);
DISPLAY INVISIBLE (-7550 3850);
FORCEPROP 1 LAST BODY_TYPE PLUMBING
J 0
(-6745 3732);
DISPLAY 0.340426 (-6745 3732);
PAINT GREEN (-6745 3732);
DISPLAY INVISIBLE (-6745 3732);
FORCEPROP 2 LAST CDS_LIB mstr_symbols
J 0
(-6700 3775);
PAINT MONO (-6700 3775);
DISPLAY INVISIBLE (-6700 3775);
FORCEPROP 1 LAST VOLTAGE 0
J 0
(-6700 3775);
PAINT SKYBLUE (-6700 3775);
DISPLAY INVISIBLE (-6700 3775);
FORCEPROP 1 LAST HDL_POWER GND
J 0
(-6700 3925);
DISPLAY 0.872340 (-6700 3925);
PAINT GREEN (-6700 3925);
DISPLAY INVISIBLE (-6700 3925);
FORCEPROP 1 LAST PATH I249
J 0
(-6625 3775);
DISPLAY 0.872340 (-6625 3775);
PAINT AQUA (-6625 3775);
DISPLAY INVISIBLE (-6625 3775);
FORCEPROP 1 LAST SIZE 1B
J 0
(-6625 3725);
DISPLAY 0.872340 (-6625 3725);
PAINT GREEN (-6625 3725);
DISPLAY INVISIBLE (-6625 3725);
FORCEADD GND..1
(-6300 3775);
FORCEPROP 3 LASTPIN (-6300 3825) SIG_NAME GND\g
J 0
(-6290 3835);
DISPLAY 0.659574 (-6290 3835);
PAINT MONO (-6290 3835);
DISPLAY INVISIBLE (-6290 3835);
FORCEPROP 2 LAST BOM_COST PVPP_KLM_VR
J 0
(-7150 3850);
DISPLAY 1.042553 (-7150 3850);
PAINT WHITE (-7150 3850);
DISPLAY INVISIBLE (-7150 3850);
FORCEPROP 2 LAST ROOM PVPP_KLM_VR
J 0
(-6875 3850);
DISPLAY 1.042553 (-6875 3850);
PAINT GREEN (-6875 3850);
DISPLAY INVISIBLE (-6875 3850);
FORCEPROP 1 LAST PATH I250
J 0
(-6225 3775);
DISPLAY 0.872340 (-6225 3775);
PAINT AQUA (-6225 3775);
DISPLAY INVISIBLE (-6225 3775);
FORCEPROP 1 LAST BODY_TYPE PLUMBING
J 0
(-6345 3732);
DISPLAY 0.340426 (-6345 3732);
PAINT GREEN (-6345 3732);
DISPLAY INVISIBLE (-6345 3732);
FORCEPROP 2 LAST CDS_LIB mstr_symbols
J 0
(-6300 3775);
PAINT MONO (-6300 3775);
DISPLAY INVISIBLE (-6300 3775);
FORCEPROP 1 LAST SIZE 1B
J 0
(-6225 3725);
DISPLAY 0.872340 (-6225 3725);
PAINT GREEN (-6225 3725);
DISPLAY INVISIBLE (-6225 3725);
FORCEPROP 1 LAST VOLTAGE 0
J 0
(-6300 3775);
PAINT SKYBLUE (-6300 3775);
DISPLAY INVISIBLE (-6300 3775);
FORCEPROP 1 LAST HDL_POWER GND
J 0
(-6300 3925);
DISPLAY 0.872340 (-6300 3925);
PAINT GREEN (-6300 3925);
DISPLAY INVISIBLE (-6300 3925);
FORCEADD GND..1
(-5875 3775);
FORCEPROP 3 LASTPIN (-5875 3825) SIG_NAME GND\g
J 0
(-5865 3835);
DISPLAY 0.659574 (-5865 3835);
PAINT MONO (-5865 3835);
DISPLAY INVISIBLE (-5865 3835);
FORCEPROP 2 LAST BOM_COST PVPP_KLM_VR
J 0
(-6725 3850);
DISPLAY 1.042553 (-6725 3850);
PAINT WHITE (-6725 3850);
DISPLAY INVISIBLE (-6725 3850);
FORCEPROP 2 LAST ROOM PVPP_KLM_VR
J 0
(-6450 3850);
DISPLAY 1.042553 (-6450 3850);
PAINT GREEN (-6450 3850);
DISPLAY INVISIBLE (-6450 3850);
FORCEPROP 1 LAST BODY_TYPE PLUMBING
J 0
(-5920 3732);
DISPLAY 0.340426 (-5920 3732);
PAINT GREEN (-5920 3732);
DISPLAY INVISIBLE (-5920 3732);
FORCEPROP 1 LAST PATH I251
J 0
(-5800 3775);
DISPLAY 0.872340 (-5800 3775);
PAINT AQUA (-5800 3775);
DISPLAY INVISIBLE (-5800 3775);
FORCEPROP 2 LAST CDS_LIB mstr_symbols
J 0
(-5875 3775);
PAINT MONO (-5875 3775);
DISPLAY INVISIBLE (-5875 3775);
FORCEPROP 1 LAST SIZE 1B
J 0
(-5800 3725);
DISPLAY 0.872340 (-5800 3725);
PAINT GREEN (-5800 3725);
DISPLAY INVISIBLE (-5800 3725);
FORCEPROP 1 LAST VOLTAGE 0
J 0
(-5875 3775);
PAINT SKYBLUE (-5875 3775);
DISPLAY INVISIBLE (-5875 3775);
FORCEPROP 1 LAST HDL_POWER GND
J 0
(-5875 3925);
DISPLAY 0.872340 (-5875 3925);
PAINT GREEN (-5875 3925);
DISPLAY INVISIBLE (-5875 3925);
FORCEADD GND..1
(-5450 3775);
FORCEPROP 3 LASTPIN (-5450 3825) SIG_NAME GND\g
J 0
(-5440 3835);
DISPLAY 0.659574 (-5440 3835);
PAINT MONO (-5440 3835);
DISPLAY INVISIBLE (-5440 3835);
FORCEPROP 2 LAST BOM_COST PVPP_KLM_VR
J 0
(-6300 3850);
DISPLAY 1.042553 (-6300 3850);
PAINT WHITE (-6300 3850);
DISPLAY INVISIBLE (-6300 3850);
FORCEPROP 2 LAST ROOM PVPP_KLM_VR
J 0
(-6025 3850);
DISPLAY 1.042553 (-6025 3850);
PAINT GREEN (-6025 3850);
DISPLAY INVISIBLE (-6025 3850);
FORCEPROP 1 LAST BODY_TYPE PLUMBING
J 0
(-5495 3732);
DISPLAY 0.340426 (-5495 3732);
PAINT GREEN (-5495 3732);
DISPLAY INVISIBLE (-5495 3732);
FORCEPROP 2 LAST CDS_LIB mstr_symbols
J 0
(-5450 3775);
PAINT MONO (-5450 3775);
DISPLAY INVISIBLE (-5450 3775);
FORCEPROP 1 LAST VOLTAGE 0
J 0
(-5450 3775);
PAINT SKYBLUE (-5450 3775);
DISPLAY INVISIBLE (-5450 3775);
FORCEPROP 1 LAST HDL_POWER GND
J 0
(-5450 3925);
DISPLAY 0.872340 (-5450 3925);
PAINT GREEN (-5450 3925);
DISPLAY INVISIBLE (-5450 3925);
FORCEPROP 1 LAST PATH I252
J 0
(-5375 3775);
DISPLAY 0.872340 (-5375 3775);
PAINT AQUA (-5375 3775);
DISPLAY INVISIBLE (-5375 3775);
FORCEPROP 1 LAST SIZE 1B
J 0
(-5375 3725);
DISPLAY 0.872340 (-5375 3725);
PAINT GREEN (-5375 3725);
DISPLAY INVISIBLE (-5375 3725);
FORCEADD CAP..1
(-6300 3975);
FORCEPROP 1 LASTPIN (-6300 4075) $PN 1
J 0
(-6290 4055);
DISPLAY 0.617021 (-6290 4055);
PAINT ORANGE (-6290 4055);
FORCEPROP 1 LASTPIN (-6300 3875) $PN 2
J 0
(-6290 3855);
DISPLAY 0.617021 (-6290 3855);
PAINT ORANGE (-6290 3855);
FORCEPROP 1 LAST TOLERANCE 10%
J 0
(-6250 3925);
DISPLAY 0.617021 (-6250 3925);
PAINT SKYBLUE (-6250 3925);
FORCEPROP 1 LAST VOLTAGE 16V
J 0
(-6250 3975);
DISPLAY 0.617021 (-6250 3975);
PAINT SKYBLUE (-6250 3975);
FORCEPROP 1 LAST MATERIAL X6S
J 0
(-6250 3875);
DISPLAY 0.617021 (-6250 3875);
PAINT SKYBLUE (-6250 3875);
FORCEPROP 1 LAST PACK_TYPE 0805
J 0
(-6250 3775);
DISPLAY 0.617021 (-6250 3775);
PAINT SKYBLUE (-6250 3775);
FORCEPROP 1 LAST VALUE 10UF
J 0
(-6250 4025);
DISPLAY 0.617021 (-6250 4025);
PAINT SKYBLUE (-6250 4025);
FORCEPROP 1 LAST PART_NUMBER C95333-007
J 0
(-6250 3825);
DISPLAY 0.617021 (-6250 3825);
PAINT BLUE (-6250 3825);
FORCEPROP 1 LAST LOCATION C4G2
J 0
(-6250 4075);
DISPLAY 0.617021 (-6250 4075);
PAINT AQUA (-6250 4075);
FORCEPROP 2 LAST CDS_LIB mstr_discrete
J 0
(-6300 3975);
PAINT MONO (-6300 3975);
DISPLAY INVISIBLE (-6300 3975);
FORCEPROP 2 LAST CDS_LOCATION C4G2
J 0
(-6250 4075);
DISPLAY 0.617021 (-6250 4075);
PAINT AQUA (-6250 4075);
DISPLAY INVISIBLE (-6250 4075);
FORCEPROP 1 LAST PATH I253
J 0
(-6250 4125);
DISPLAY 0.978723 (-6250 4125);
PAINT WHITE (-6250 4125);
DISPLAY INVISIBLE (-6250 4125);
FORCEPROP 2 LAST SEC 1
J 0
(-6250 4175);
DISPLAY 0.680851 (-6250 4175);
PAINT MONO (-6250 4175);
DISPLAY INVISIBLE (-6250 4175);
FORCEPROP 2 LAST SEC_TYPE 0805
J 0
(-6250 4175);
DISPLAY 1.021277 (-6250 4175);
PAINT ORANGE (-6250 4175);
DISPLAY INVISIBLE (-6250 4175);
FORCEADD CAP..1
(-5875 3975);
FORCEPROP 1 LAST PACK_TYPE 0805
J 0
(-5825 3775);
DISPLAY 0.617021 (-5825 3775);
PAINT SKYBLUE (-5825 3775);
FORCEPROP 1 LAST VALUE 10UF
J 0
(-5825 4025);
DISPLAY 0.617021 (-5825 4025);
PAINT SKYBLUE (-5825 4025);
FORCEPROP 1 LAST TOLERANCE 10%
J 0
(-5825 3925);
DISPLAY 0.617021 (-5825 3925);
PAINT SKYBLUE (-5825 3925);
FORCEPROP 1 LAST VOLTAGE 16V
J 0
(-5825 3975);
DISPLAY 0.617021 (-5825 3975);
PAINT SKYBLUE (-5825 3975);
FORCEPROP 1 LAST MATERIAL X6S
J 0
(-5825 3875);
DISPLAY 0.617021 (-5825 3875);
PAINT SKYBLUE (-5825 3875);
FORCEPROP 1 LASTPIN (-5875 3875) $PN 2
J 0
(-5865 3855);
DISPLAY 0.617021 (-5865 3855);
PAINT ORANGE (-5865 3855);
FORCEPROP 1 LASTPIN (-5875 4075) $PN 1
J 0
(-5865 4055);
DISPLAY 0.617021 (-5865 4055);
PAINT ORANGE (-5865 4055);
FORCEPROP 1 LAST PART_NUMBER C95333-007
J 0
(-5825 3825);
DISPLAY 0.617021 (-5825 3825);
PAINT BLUE (-5825 3825);
FORCEPROP 1 LAST LOCATION C6U7
J 0
(-5825 4075);
DISPLAY 0.617021 (-5825 4075);
PAINT AQUA (-5825 4075);
FORCEPROP 2 LAST CDS_LIB mstr_discrete
J 0
(-5875 3975);
PAINT MONO (-5875 3975);
DISPLAY INVISIBLE (-5875 3975);
FORCEPROP 2 LAST CDS_LOCATION C6U7
J 0
(-5825 4075);
DISPLAY 0.617021 (-5825 4075);
PAINT AQUA (-5825 4075);
DISPLAY INVISIBLE (-5825 4075);
FORCEPROP 1 LAST PATH I254
J 0
(-5825 4125);
DISPLAY 0.978723 (-5825 4125);
PAINT WHITE (-5825 4125);
DISPLAY INVISIBLE (-5825 4125);
FORCEPROP 2 LAST SEC 1
J 0
(-5825 4175);
DISPLAY 0.680851 (-5825 4175);
PAINT MONO (-5825 4175);
DISPLAY INVISIBLE (-5825 4175);
FORCEPROP 2 LAST SEC_TYPE 0805
J 0
(-5825 4175);
DISPLAY 1.021277 (-5825 4175);
PAINT ORANGE (-5825 4175);
DISPLAY INVISIBLE (-5825 4175);
FORCEADD CAP..1
(-5450 3975);
FORCEPROP 1 LASTPIN (-5450 3875) $PN 2
J 0
(-5440 3855);
DISPLAY 0.617021 (-5440 3855);
PAINT ORANGE (-5440 3855);
FORCEPROP 1 LASTPIN (-5450 4075) $PN 1
J 0
(-5440 4055);
DISPLAY 0.617021 (-5440 4055);
PAINT ORANGE (-5440 4055);
FORCEPROP 1 LAST MATERIAL X6S
J 0
(-5400 3875);
DISPLAY 0.617021 (-5400 3875);
PAINT SKYBLUE (-5400 3875);
FORCEPROP 1 LAST VOLTAGE 16V
J 0
(-5400 3975);
DISPLAY 0.617021 (-5400 3975);
PAINT SKYBLUE (-5400 3975);
FORCEPROP 1 LAST PACK_TYPE 0805
J 0
(-5400 3775);
DISPLAY 0.617021 (-5400 3775);
PAINT SKYBLUE (-5400 3775);
FORCEPROP 1 LAST TOLERANCE 10%
J 0
(-5400 3925);
DISPLAY 0.617021 (-5400 3925);
PAINT SKYBLUE (-5400 3925);
FORCEPROP 1 LAST VALUE 10UF
J 0
(-5400 4025);
DISPLAY 0.617021 (-5400 4025);
PAINT SKYBLUE (-5400 4025);
FORCEPROP 1 LAST PART_NUMBER C95333-007
J 0
(-5400 3825);
DISPLAY 0.617021 (-5400 3825);
PAINT BLUE (-5400 3825);
FORCEPROP 1 LAST LOCATION C6U8
J 0
(-5400 4075);
DISPLAY 0.617021 (-5400 4075);
PAINT AQUA (-5400 4075);
FORCEPROP 2 LAST CDS_LIB mstr_discrete
J 0
(-5450 3975);
PAINT MONO (-5450 3975);
DISPLAY INVISIBLE (-5450 3975);
FORCEPROP 2 LAST CDS_LOCATION C6U8
J 0
(-5400 4075);
DISPLAY 0.617021 (-5400 4075);
PAINT AQUA (-5400 4075);
DISPLAY INVISIBLE (-5400 4075);
FORCEPROP 1 LAST PATH I255
J 0
(-5400 4125);
DISPLAY 0.978723 (-5400 4125);
PAINT WHITE (-5400 4125);
DISPLAY INVISIBLE (-5400 4125);
FORCEPROP 2 LAST SEC 1
J 0
(-5400 4175);
DISPLAY 0.680851 (-5400 4175);
PAINT MONO (-5400 4175);
DISPLAY INVISIBLE (-5400 4175);
FORCEPROP 2 LAST SEC_TYPE 0805
J 0
(-5400 4175);
DISPLAY 1.021277 (-5400 4175);
PAINT ORANGE (-5400 4175);
DISPLAY INVISIBLE (-5400 4175);
FORCEADD CAPP..1
(-1375 3500);
FORCEPROP 1 LASTPIN (-1375 3400) $PN 2
J 0
(-1365 3385);
DISPLAY 0.617021 (-1365 3385);
PAINT ORANGE (-1365 3385);
FORCEPROP 1 LAST MATERIAL POSCAP
J 0
(-1325 3400);
DISPLAY 0.617021 (-1325 3400);
PAINT SKYBLUE (-1325 3400);
FORCEPROP 1 LAST VOLTAGE 4V
J 0
(-1325 3450);
DISPLAY 0.617021 (-1325 3450);
PAINT SKYBLUE (-1325 3450);
FORCEPROP 1 LAST PACK_TYPE 7343
J 0
(-1325 3350);
DISPLAY 0.617021 (-1325 3350);
PAINT SKYBLUE (-1325 3350);
FORCEPROP 1 LAST TOLERANCE 20%
J 0
(-1325 3500);
DISPLAY 0.617021 (-1325 3500);
PAINT SKYBLUE (-1325 3500);
FORCEPROP 1 LAST VALUE 220UF
J 0
(-1325 3550);
DISPLAY 0.617021 (-1325 3550);
PAINT SKYBLUE (-1325 3550);
FORCEPROP 1 LAST PART_NUMBER 724613-067
J 0
(-1325 3300);
DISPLAY 0.617021 (-1325 3300);
PAINT BLUE (-1325 3300);
FORCEPROP 1 LASTPIN (-1375 3600) $PN 1
J 0
(-1365 3585);
DISPLAY 0.617021 (-1365 3585);
PAINT ORANGE (-1365 3585);
FORCEPROP 1 LAST LOCATION C4F11
J 0
(-1325 3600);
DISPLAY 0.617021 (-1325 3600);
PAINT AQUA (-1325 3600);
FORCEPROP 2 LAST CDS_LIB mstr_discrete
J 0
(-1375 3500);
PAINT ORANGE (-1375 3500);
DISPLAY INVISIBLE (-1375 3500);
FORCEPROP 2 LAST SEC_TYPE 7343
J 0
(-1325 3700);
DISPLAY 1.021277 (-1325 3700);
PAINT ORANGE (-1325 3700);
DISPLAY INVISIBLE (-1325 3700);
FORCEPROP 2 LAST SEC 1
J 0
(-1325 3700);
DISPLAY 0.680851 (-1325 3700);
PAINT MONO (-1325 3700);
DISPLAY INVISIBLE (-1325 3700);
FORCEPROP 2 LAST CDS_LOCATION C4F11
J 0
(-1325 3600);
DISPLAY 0.617021 (-1325 3600);
PAINT AQUA (-1325 3600);
DISPLAY INVISIBLE (-1325 3600);
FORCEPROP 1 LAST PATH I256
J 0
(-1325 3650);
DISPLAY 0.978723 (-1325 3650);
PAINT ORANGE (-1325 3650);
DISPLAY INVISIBLE (-1325 3650);
FORCEADD RES..2
(-950 2475);
FORCEPROP 1 LASTPIN (-950 2375) $PN 2
J 0
(-945 2385);
DISPLAY 0.617021 (-945 2385);
PAINT ORANGE (-945 2385);
FORCEPROP 1 LAST MATERIAL CHIP
J 0
(-910 2350);
DISPLAY 0.617021 (-910 2350);
PAINT SKYBLUE (-910 2350);
FORCEPROP 1 LAST PACK_TYPE 0402
J 0
(-910 2400);
DISPLAY 0.617021 (-910 2400);
PAINT SKYBLUE (-910 2400);
FORCEPROP 1 LAST TOLERANCE 0.1%
J 0
(-905 2500);
DISPLAY 0.617021 (-905 2500);
PAINT SKYBLUE (-905 2500);
FORCEPROP 1 LAST WATTAGE 1/16W
J 0
(-910 2450);
DISPLAY 0.617021 (-910 2450);
PAINT SKYBLUE (-910 2450);
FORCEPROP 1 LAST PART_NUMBER G85996-004
J 0
(-935 2300);
DISPLAY 0.617021 (-935 2300);
PAINT BLUE (-935 2300);
FORCEPROP 1 LASTPIN (-950 2575) $PN 1
J 0
(-945 2537);
DISPLAY 0.617021 (-945 2537);
PAINT ORANGE (-945 2537);
FORCEPROP 1 LAST VALUE 1.0K
J 0
(-905 2550);
DISPLAY 0.617021 (-905 2550);
PAINT SKYBLUE (-905 2550);
FORCEPROP 1 LAST LOCATION R4G10
J 0
(-905 2600);
DISPLAY 0.617021 (-905 2600);
PAINT AQUA (-905 2600);
FORCEPROP 2 LAST CDS_LIB mstr_discrete
J 0
(-950 2475);
PAINT MONO (-950 2475);
DISPLAY INVISIBLE (-950 2475);
FORCEPROP 0 LAST SPOF TRUE
J 0
(-900 2700);
DISPLAY 1.021277 (-900 2700);
PAINT ORANGE (-900 2700);
DISPLAY INVISIBLE (-900 2700);
FORCEPROP 2 LAST SEC_TYPE 0402
J 0
(-900 2700);
DISPLAY 1.021277 (-900 2700);
PAINT ORANGE (-900 2700);
DISPLAY INVISIBLE (-900 2700);
FORCEPROP 2 LAST REUSE_ID 9
J 0
(-900 2700);
DISPLAY 1.042553 (-900 2700);
PAINT ORANGE (-900 2700);
DISPLAY INVISIBLE (-900 2700);
FORCEPROP 2 LAST BOM_COST PVPP_KLM_VR
J 0
(-905 2655);
DISPLAY 1.042553 (-905 2655);
PAINT WHITE (-905 2655);
DISPLAY INVISIBLE (-905 2655);
FORCEPROP 2 LAST SEC 1
J 0
(-900 2700);
DISPLAY 0.680851 (-900 2700);
PAINT MONO (-900 2700);
DISPLAY INVISIBLE (-900 2700);
FORCEPROP 2 LAST CDS_LOCATION R4G10
J 0
(-905 2600);
DISPLAY 0.617021 (-905 2600);
PAINT AQUA (-905 2600);
DISPLAY INVISIBLE (-905 2600);
FORCEPROP 1 LAST PATH I266
J 0
(-900 2650);
DISPLAY 0.978723 (-900 2650);
PAINT WHITE (-900 2650);
DISPLAY INVISIBLE (-900 2650);
FORCEPROP 2 LAST ROOM PVPP_KLM_VR
J 0
(-905 2630);
PAINT GREEN (-905 2630);
DISPLAY INVISIBLE (-905 2630);
FORCEADD CAP..1
(-950 1925);
FORCEPROP 1 LAST TOLERANCE 10%
J 0
(-900 1875);
DISPLAY 0.617021 (-900 1875);
PAINT SKYBLUE (-900 1875);
FORCEPROP 1 LASTPIN (-950 2025) $PN 1
J 0
(-940 2005);
DISPLAY 0.617021 (-940 2005);
PAINT ORANGE (-940 2005);
FORCEPROP 1 LASTPIN (-950 1825) $PN 2
J 0
(-940 1805);
DISPLAY 0.617021 (-940 1805);
PAINT ORANGE (-940 1805);
FORCEPROP 1 LAST MATERIAL X7R
J 0
(-900 1825);
DISPLAY 0.617021 (-900 1825);
PAINT SKYBLUE (-900 1825);
FORCEPROP 1 LAST VOLTAGE 50V
J 0
(-900 1925);
DISPLAY 0.617021 (-900 1925);
PAINT SKYBLUE (-900 1925);
FORCEPROP 1 LAST PART_NUMBER A36096-075
J 0
(-900 1775);
DISPLAY 0.617021 (-900 1775);
PAINT BLUE (-900 1775);
FORCEPROP 1 LAST VALUE 2200PF
J 0
(-900 1975);
DISPLAY 0.617021 (-900 1975);
PAINT SKYBLUE (-900 1975);
FORCEPROP 1 LAST PACK_TYPE 0402LF
J 0
(-900 1725);
DISPLAY 0.617021 (-900 1725);
PAINT SKYBLUE (-900 1725);
FORCEPROP 1 LAST LOCATION C4G11
J 0
(-900 2025);
DISPLAY 0.617021 (-900 2025);
PAINT AQUA (-900 2025);
FORCEPROP 2 LAST CDS_LIB mstr_discrete
J 0
(-950 1925);
PAINT ORANGE (-950 1925);
DISPLAY INVISIBLE (-950 1925);
FORCEPROP 2 LAST CDS_LOCATION C4G11
J 0
(-900 2025);
DISPLAY 0.617021 (-900 2025);
PAINT AQUA (-900 2025);
DISPLAY INVISIBLE (-900 2025);
FORCEPROP 2 LAST ROOM PVPP_KLM_VR
J 0
(-900 2050);
PAINT GREEN (-900 2050);
DISPLAY INVISIBLE (-900 2050);
FORCEPROP 2 LAST BOM_COST PVPP_KLM_VR
J 0
(-900 2075);
DISPLAY 1.042553 (-900 2075);
PAINT WHITE (-900 2075);
DISPLAY INVISIBLE (-900 2075);
FORCEPROP 2 LAST SEC 1
J 0
(-900 2125);
DISPLAY 0.680851 (-900 2125);
PAINT MONO (-900 2125);
DISPLAY INVISIBLE (-900 2125);
FORCEPROP 2 LAST SEC_TYPE 0402LF
J 0
(-900 2125);
DISPLAY 1.021277 (-900 2125);
PAINT ORANGE (-900 2125);
DISPLAY INVISIBLE (-900 2125);
FORCEPROP 0 LAST SPOF TRUE
J 0
(-900 2125);
DISPLAY 1.021277 (-900 2125);
PAINT ORANGE (-900 2125);
DISPLAY INVISIBLE (-900 2125);
FORCEPROP 1 LAST PATH I267
J 0
(-900 2075);
DISPLAY 0.978723 (-900 2075);
PAINT WHITE (-900 2075);
DISPLAY INVISIBLE (-900 2075);
FORCEPROP 2 LAST REUSE_ID 26
J 0
(-900 2125);
DISPLAY 1.042553 (-900 2125);
PAINT ORANGE (-900 2125);
DISPLAY INVISIBLE (-900 2125);
FORCEADD RES..2
(-1275 1400);
FORCEPROP 1 LAST PACK_TYPE 0402
J 0
(-1235 1225);
DISPLAY 0.617021 (-1235 1225);
PAINT SKYBLUE (-1235 1225);
FORCEPROP 1 LAST WATTAGE 1/16W
J 0
(-1235 1375);
DISPLAY 0.617021 (-1235 1375);
PAINT SKYBLUE (-1235 1375);
FORCEPROP 1 LAST MATERIAL CHIP
J 0
(-1235 1325);
DISPLAY 0.617021 (-1235 1325);
PAINT SKYBLUE (-1235 1325);
FORCEPROP 1 LAST VALUE 6.34K
J 0
(-1230 1475);
DISPLAY 0.617021 (-1230 1475);
PAINT SKYBLUE (-1230 1475);
FORCEPROP 1 LASTPIN (-1275 1300) $PN 2
J 0
(-1270 1310);
DISPLAY 0.617021 (-1270 1310);
PAINT WHITE (-1270 1310);
FORCEPROP 1 LASTPIN (-1275 1500) $PN 1
J 0
(-1270 1462);
DISPLAY 0.617021 (-1270 1462);
PAINT WHITE (-1270 1462);
FORCEPROP 1 LAST TOLERANCE 1%
J 0
(-1230 1425);
DISPLAY 0.617021 (-1230 1425);
PAINT SKYBLUE (-1230 1425);
FORCEPROP 1 LAST LOCATION R4G9
J 0
(-1230 1525);
DISPLAY 0.617021 (-1230 1525);
PAINT AQUA (-1230 1525);
FORCEPROP 1 LAST PART_NUMBER G21796-146
J 0
(-1235 1275);
DISPLAY 0.617021 (-1235 1275);
PAINT BLUE (-1235 1275);
FORCEPROP 2 LAST BOM_COST PVPP_KLM_VR
R 1
J 0
(-1575 1450);
DISPLAY 1.042553 (-1575 1450);
PAINT WHITE (-1575 1450);
DISPLAY INVISIBLE (-1575 1450);
FORCEPROP 2 LAST ROOM PVPP_KLM_VR
R 1
J 0
(-1475 1450);
DISPLAY 1.042553 (-1475 1450);
PAINT GREEN (-1475 1450);
DISPLAY INVISIBLE (-1475 1450);
FORCEPROP 2 LAST CDS_LIB mstr_discrete
R 1
J 0
(-1275 1400);
PAINT MONO (-1275 1400);
DISPLAY INVISIBLE (-1275 1400);
FORCEPROP 2 LAST CDS_LOCATION R4G9
J 0
(-1230 1525);
DISPLAY 0.617021 (-1230 1525);
PAINT AQUA (-1230 1525);
DISPLAY INVISIBLE (-1230 1525);
FORCEPROP 1 LAST PATH I269
J 0
(-1225 1575);
DISPLAY 0.978723 (-1225 1575);
PAINT WHITE (-1225 1575);
DISPLAY INVISIBLE (-1225 1575);
FORCEPROP 2 LAST $SEC 1
J 0
(-1225 1625);
DISPLAY 0.680851 (-1225 1625);
PAINT MONO (-1225 1625);
DISPLAY INVISIBLE (-1225 1625);
FORCEPROP 0 LAST SPOF TRUE
J 0
(-1225 1625);
DISPLAY 1.021277 (-1225 1625);
PAINT ORANGE (-1225 1625);
DISPLAY INVISIBLE (-1225 1625);
FORCEPROP 2 LAST REUSE_ID 7
J 0
(-1225 1625);
DISPLAY 1.042553 (-1225 1625);
PAINT ORANGE (-1225 1625);
DISPLAY INVISIBLE (-1225 1625);
FORCEPROP 2 LAST CDS_SEC 1
J 0
(-1225 1625);
DISPLAY 1.042553 (-1225 1625);
PAINT ORANGE (-1225 1625);
DISPLAY INVISIBLE (-1225 1625);
FORCEADD RES..2
(-1275 2025);
FORCEPROP 1 LASTPIN (-1275 1925) $PN 2
J 0
(-1270 1935);
DISPLAY 0.617021 (-1270 1935);
PAINT WHITE (-1270 1935);
FORCEPROP 1 LAST WATTAGE 1/16W
J 0
(-1235 2000);
DISPLAY 0.617021 (-1235 2000);
PAINT SKYBLUE (-1235 2000);
FORCEPROP 1 LAST MATERIAL CHIP
J 0
(-1235 1900);
DISPLAY 0.617021 (-1235 1900);
PAINT SKYBLUE (-1235 1900);
FORCEPROP 1 LAST PACK_TYPE 0402
J 0
(-1235 1950);
DISPLAY 0.617021 (-1235 1950);
PAINT SKYBLUE (-1235 1950);
FORCEPROP 1 LAST PART_NUMBER G21796-040
J 0
(-1260 1850);
DISPLAY 0.617021 (-1260 1850);
PAINT BLUE (-1260 1850);
FORCEPROP 1 LAST LOCATION R4G7
J 0
(-1230 2150);
DISPLAY 0.617021 (-1230 2150);
PAINT AQUA (-1230 2150);
FORCEPROP 1 LAST VALUE 20.0K
J 0
(-1230 2100);
DISPLAY 0.617021 (-1230 2100);
PAINT SKYBLUE (-1230 2100);
FORCEPROP 1 LAST TOLERANCE 1%
J 0
(-1230 2050);
DISPLAY 0.617021 (-1230 2050);
PAINT SKYBLUE (-1230 2050);
FORCEPROP 1 LASTPIN (-1275 2125) $PN 1
J 0
(-1270 2087);
DISPLAY 0.617021 (-1270 2087);
PAINT WHITE (-1270 2087);
FORCEPROP 2 LAST CDS_LIB mstr_discrete
J 0
(-1275 2025);
PAINT MONO (-1275 2025);
DISPLAY INVISIBLE (-1275 2025);
FORCEPROP 2 LAST BOM_COST PVPP_KLM_VR
J 0
(-1230 2205);
DISPLAY 1.042553 (-1230 2205);
PAINT WHITE (-1230 2205);
DISPLAY INVISIBLE (-1230 2205);
FORCEPROP 2 LAST REUSE_ID 9
J 0
(-1225 2250);
DISPLAY 1.042553 (-1225 2250);
PAINT ORANGE (-1225 2250);
DISPLAY INVISIBLE (-1225 2250);
FORCEPROP 0 LAST SPOF TRUE
J 0
(-1225 2250);
DISPLAY 1.021277 (-1225 2250);
PAINT ORANGE (-1225 2250);
DISPLAY INVISIBLE (-1225 2250);
FORCEPROP 2 LAST CDS_SEC 1
J 0
(-1225 2250);
DISPLAY 1.042553 (-1225 2250);
PAINT ORANGE (-1225 2250);
DISPLAY INVISIBLE (-1225 2250);
FORCEPROP 2 LAST $SEC 1
J 0
(-1225 2250);
DISPLAY 0.680851 (-1225 2250);
PAINT MONO (-1225 2250);
DISPLAY INVISIBLE (-1225 2250);
FORCEPROP 2 LAST CDS_LOCATION R4G7
J 0
(-1230 2150);
DISPLAY 0.617021 (-1230 2150);
PAINT AQUA (-1230 2150);
DISPLAY INVISIBLE (-1230 2150);
FORCEPROP 1 LAST PATH I270
J 0
(-1225 2200);
DISPLAY 0.978723 (-1225 2200);
PAINT WHITE (-1225 2200);
DISPLAY INVISIBLE (-1225 2200);
FORCEPROP 2 LAST ROOM PVPP_KLM_VR
J 0
(-1230 2180);
PAINT GREEN (-1230 2180);
DISPLAY INVISIBLE (-1230 2180);
FORCEADD RES..1
R 5
(-1275 2775);
FORCEPROP 1 LASTPIN (-1275 2675) $PN 2
J 0
(-1263 2713);
DISPLAY 0.617021 (-1263 2713);
PAINT ORANGE (-1263 2713);
FORCEPROP 1 LAST TOLERANCE 5%
J 0
(-1250 2725);
DISPLAY 0.617021 (-1250 2725);
PAINT SKYBLUE (-1250 2725);
FORCEPROP 1 LAST LOCATION R4G8
J 0
(-1175 2725);
DISPLAY 0.617021 (-1175 2725);
PAINT AQUA (-1175 2725);
FORCEPROP 1 LAST PACK_TYPE 0402
J 0
(-1250 2625);
DISPLAY 0.617021 (-1250 2625);
PAINT SKYBLUE (-1250 2625);
FORCEPROP 1 LAST MATERIAL CHIP
J 0
(-1250 2675);
DISPLAY 0.617021 (-1250 2675);
PAINT SKYBLUE (-1250 2675);
FORCEPROP 1 LAST WATTAGE 1/16W
J 0
(-1250 2775);
DISPLAY 0.617021 (-1250 2775);
PAINT SKYBLUE (-1250 2775);
FORCEPROP 1 LAST VALUE 0.0
J 0
(-1225 2825);
DISPLAY 0.617021 (-1225 2825);
PAINT SKYBLUE (-1225 2825);
FORCEPROP 1 LASTPIN (-1275 2875) $PN 1
J 0
(-1263 2863);
DISPLAY 0.617021 (-1263 2863);
PAINT ORANGE (-1263 2863);
FORCEPROP 1 LAST PART_NUMBER G21497-005
J 0
(-1250 2575);
DISPLAY 0.617021 (-1250 2575);
PAINT BLUE (-1250 2575);
FORCEPROP 2 LAST CDS_LOCATION R4G8
J 0
(-1175 2725);
DISPLAY 0.617021 (-1175 2725);
PAINT AQUA (-1175 2725);
DISPLAY INVISIBLE (-1175 2725);
FORCEPROP 2 LAST CDS_LIB mstr_discrete
J 0
(-1275 2775);
PAINT ORANGE (-1275 2775);
DISPLAY INVISIBLE (-1275 2775);
FORCEPROP 2 LAST SEC_TYPE 0402
J 0
(-1200 2925);
DISPLAY 1.021277 (-1200 2925);
PAINT ORANGE (-1200 2925);
DISPLAY INVISIBLE (-1200 2925);
FORCEPROP 0 LAST SPOF TRUE
J 0
(-1225 2925);
DISPLAY 1.021277 (-1225 2925);
PAINT ORANGE (-1225 2925);
DISPLAY INVISIBLE (-1225 2925);
FORCEPROP 2 LAST ROOM PVPP_KLM_VR
R 3
J 0
(-1125 2825);
DISPLAY 1.659574 (-1125 2825);
PAINT GREEN (-1125 2825);
DISPLAY INVISIBLE (-1125 2825);
FORCEPROP 1 LAST PATH I271
R 3
J 0
(-1125 2825);
DISPLAY 0.978723 (-1125 2825);
PAINT WHITE (-1125 2825);
DISPLAY INVISIBLE (-1125 2825);
FORCEPROP 2 LAST SEC 1
J 0
(-1200 2925);
DISPLAY 0.680851 (-1200 2925);
PAINT MONO (-1200 2925);
DISPLAY INVISIBLE (-1200 2925);
FORCEADD RES..1
(-2075 2300);
FORCEPROP 1 LAST VALUE 7.87K
J 2
(-2175 2175);
DISPLAY 0.617021 (-2175 2175);
PAINT SKYBLUE (-2175 2175);
FORCEPROP 1 LAST WATTAGE 1/16W
J 2
(-2100 2125);
DISPLAY 0.617021 (-2100 2125);
PAINT SKYBLUE (-2100 2125);
FORCEPROP 1 LASTPIN (-2175 2300) $PN 1
J 0
(-2163 2312);
DISPLAY 0.617021 (-2163 2312);
PAINT ORANGE (-2163 2312);
FORCEPROP 1 LAST MATERIAL CHIP
J 0
(-2075 2125);
DISPLAY 0.617021 (-2075 2125);
PAINT SKYBLUE (-2075 2125);
FORCEPROP 1 LAST TOLERANCE 1.0%
J 0
(-2125 2175);
DISPLAY 0.617021 (-2125 2175);
PAINT SKYBLUE (-2125 2175);
FORCEPROP 1 LAST PART_NUMBER G21796-242
J 0
(-2225 2225);
DISPLAY 0.617021 (-2225 2225);
PAINT BLUE (-2225 2225);
FORCEPROP 1 LAST LOCATION R4G13
J 0
(-2125 2350);
DISPLAY 0.617021 (-2125 2350);
PAINT AQUA (-2125 2350);
FORCEPROP 1 LAST PACK_TYPE 0402
J 0
(-2025 2175);
DISPLAY 0.617021 (-2025 2175);
PAINT SKYBLUE (-2025 2175);
FORCEPROP 1 LASTPIN (-1975 2300) $PN 2
J 0
(-2013 2312);
DISPLAY 0.617021 (-2013 2312);
PAINT ORANGE (-2013 2312);
FORCEPROP 2 LAST ROOM PVPP_KLM_VR
J 0
(-2075 2300);
PAINT GREEN (-2075 2300);
DISPLAY INVISIBLE (-2075 2300);
FORCEPROP 2 LAST CDS_LIB mstr_discrete
J 0
(-2075 2300);
PAINT MONO (-2075 2300);
DISPLAY INVISIBLE (-2075 2300);
FORCEPROP 2 LAST BOM_COST PVPP_KLM_VR
J 0
(-2075 2300);
PAINT WHITE (-2075 2300);
DISPLAY INVISIBLE (-2075 2300);
FORCEPROP 0 LAST SEC 1
J 0
(-2125 2400);
PAINT MONO (-2125 2400);
DISPLAY INVISIBLE (-2125 2400);
FORCEPROP 1 LAST PATH I272
J 0
(-2125 2450);
DISPLAY 0.978723 (-2125 2450);
PAINT WHITE (-2125 2450);
DISPLAY INVISIBLE (-2125 2450);
FORCEPROP 2 LAST CDS_LOCATION R4G13
J 0
(-2125 2350);
DISPLAY 0.617021 (-2125 2350);
PAINT AQUA (-2125 2350);
DISPLAY INVISIBLE (-2125 2350);
FORCEPROP 2 LAST REUSE_ID 13
J 0
(-2125 2500);
DISPLAY 1.042553 (-2125 2500);
PAINT ORANGE (-2125 2500);
DISPLAY INVISIBLE (-2125 2500);
FORCEPROP 2 LAST SEC_TYPE 0402
J 0
(-2125 2500);
DISPLAY 1.021277 (-2125 2500);
PAINT ORANGE (-2125 2500);
DISPLAY INVISIBLE (-2125 2500);
FORCEADD CAP..2
R 2
(-2350 2675);
FORCEPROP 1 LAST PART_NUMBER A36095-026
J 1
(-2675 2575);
DISPLAY 0.617021 (-2675 2575);
PAINT BLUE (-2675 2575);
FORCEPROP 1 LAST PACK_TYPE 0402LF
J 1
(-2375 2525);
DISPLAY 0.617021 (-2375 2525);
PAINT SKYBLUE (-2375 2525);
FORCEPROP 1 LAST VOLTAGE 50V
J 2
(-2350 2575);
DISPLAY 0.617021 (-2350 2575);
PAINT SKYBLUE (-2350 2575);
FORCEPROP 1 LASTPIN (-2450 2675) $PN 2
J 2
(-2435 2690);
DISPLAY 0.617021 (-2435 2690);
PAINT ORANGE (-2435 2690);
FORCEPROP 1 LAST VALUE 100.0PF
J 0
(-2350 2575);
DISPLAY 0.617021 (-2350 2575);
PAINT SKYBLUE (-2350 2575);
FORCEPROP 1 LAST LOCATION C4G6
J 1
(-2350 2725);
DISPLAY 0.617021 (-2350 2725);
PAINT AQUA (-2350 2725);
FORCEPROP 1 LASTPIN (-2250 2675) $PN 1
J 2
(-2240 2690);
DISPLAY 0.617021 (-2240 2690);
PAINT ORANGE (-2240 2690);
FORCEPROP 1 LAST MATERIAL COG
J 2
(-1975 2575);
DISPLAY 0.617021 (-1975 2575);
PAINT SKYBLUE (-1975 2575);
FORCEPROP 1 LAST TOLERANCE 5%
J 0
(-1975 2575);
DISPLAY 0.617021 (-1975 2575);
PAINT SKYBLUE (-1975 2575);
FORCEPROP 2 LAST CDS_LIB mstr_discrete
J 0
(-2350 2675);
PAINT ORANGE (-2350 2675);
DISPLAY INVISIBLE (-2350 2675);
FORCEPROP 2 LAST CDS_LOCATION C4G6
J 1
(-2350 2725);
DISPLAY 0.617021 (-2350 2725);
PAINT AQUA (-2350 2725);
DISPLAY INVISIBLE (-2350 2725);
FORCEPROP 2 LAST ROOM PVPP_KLM_VR
J 2
(-2350 2800);
DISPLAY 0.765957 (-2350 2800);
PAINT GREEN (-2350 2800);
DISPLAY INVISIBLE (-2350 2800);
FORCEPROP 1 LAST PATH I273
J 2
(-2350 2875);
DISPLAY 0.978723 (-2350 2875);
PAINT WHITE (-2350 2875);
DISPLAY INVISIBLE (-2350 2875);
FORCEPROP 2 LAST SEC 1
J 0
(-2350 2925);
DISPLAY 0.680851 (-2350 2925);
PAINT MONO (-2350 2925);
DISPLAY INVISIBLE (-2350 2925);
FORCEPROP 2 LAST BOM_COST PVPP_KLM_VR
J 0
(-2395 2835);
DISPLAY 1.042553 (-2395 2835);
PAINT WHITE (-2395 2835);
DISPLAY INVISIBLE (-2395 2835);
FORCEPROP 2 LAST REUSE_ID 27
J 0
(-2350 2925);
DISPLAY 1.042553 (-2350 2925);
PAINT ORANGE (-2350 2925);
DISPLAY INVISIBLE (-2350 2925);
FORCEPROP 2 LAST SEC_TYPE 0402LF
J 0
(-2350 2925);
DISPLAY 1.021277 (-2350 2925);
PAINT ORANGE (-2350 2925);
DISPLAY INVISIBLE (-2350 2925);
FORCEADD CAP..2
R 2
(-2775 2300);
FORCEPROP 1 LASTPIN (-2875 2300) $PN 2
J 2
(-2860 2315);
DISPLAY 0.617021 (-2860 2315);
PAINT ORANGE (-2860 2315);
FORCEPROP 1 LAST MATERIAL X7R
J 2
(-2750 2125);
DISPLAY 0.617021 (-2750 2125);
PAINT SKYBLUE (-2750 2125);
FORCEPROP 1 LAST VOLTAGE 50V
J 2
(-2750 2175);
DISPLAY 0.617021 (-2750 2175);
PAINT SKYBLUE (-2750 2175);
FORCEPROP 1 LAST PACK_TYPE 0402LF
J 1
(-2775 2075);
DISPLAY 0.617021 (-2775 2075);
PAINT SKYBLUE (-2775 2075);
FORCEPROP 1 LAST LOCATION C4G10
J 1
(-2775 2375);
DISPLAY 0.617021 (-2775 2375);
PAINT AQUA (-2775 2375);
FORCEPROP 1 LASTPIN (-2675 2300) $PN 1
J 2
(-2665 2315);
DISPLAY 0.617021 (-2665 2315);
PAINT ORANGE (-2665 2315);
FORCEPROP 1 LAST TOLERANCE 10%
J 0
(-2750 2125);
DISPLAY 0.617021 (-2750 2125);
PAINT SKYBLUE (-2750 2125);
FORCEPROP 1 LAST VALUE 2200PF
J 0
(-2750 2175);
DISPLAY 0.617021 (-2750 2175);
PAINT SKYBLUE (-2750 2175);
FORCEPROP 1 LAST PART_NUMBER A36096-075
J 1
(-2700 2225);
DISPLAY 0.617021 (-2700 2225);
PAINT BLUE (-2700 2225);
FORCEPROP 2 LAST BOM_COST PVPP_KLM_VR
J 0
(-2820 2460);
DISPLAY 1.042553 (-2820 2460);
PAINT WHITE (-2820 2460);
DISPLAY INVISIBLE (-2820 2460);
FORCEPROP 2 LAST ROOM PVPP_KLM_VR
J 2
(-2775 2425);
DISPLAY 0.765957 (-2775 2425);
PAINT GREEN (-2775 2425);
DISPLAY INVISIBLE (-2775 2425);
FORCEPROP 1 LAST PATH I274
J 2
(-2775 2500);
DISPLAY 0.978723 (-2775 2500);
PAINT WHITE (-2775 2500);
DISPLAY INVISIBLE (-2775 2500);
FORCEPROP 2 LAST CDS_LOCATION C4G10
J 1
(-2775 2375);
DISPLAY 0.617021 (-2775 2375);
PAINT AQUA (-2775 2375);
DISPLAY INVISIBLE (-2775 2375);
FORCEPROP 2 LAST CDS_LIB mstr_discrete
J 0
(-2775 2300);
PAINT ORANGE (-2775 2300);
DISPLAY INVISIBLE (-2775 2300);
FORCEPROP 2 LAST SEC 1
J 0
(-2775 2550);
DISPLAY 0.680851 (-2775 2550);
PAINT MONO (-2775 2550);
DISPLAY INVISIBLE (-2775 2550);
FORCEPROP 2 LAST REUSE_ID 27
J 0
(-2775 2550);
DISPLAY 1.042553 (-2775 2550);
PAINT ORANGE (-2775 2550);
DISPLAY INVISIBLE (-2775 2550);
FORCEPROP 2 LAST SEC_TYPE 0402LF
J 0
(-2775 2550);
DISPLAY 1.021277 (-2775 2550);
PAINT ORANGE (-2775 2550);
DISPLAY INVISIBLE (-2775 2550);
FORCEADD RES..1
(-6000 2675);
FORCEPROP 1 LAST WATTAGE 1/16W
J 2
(-6025 2525);
DISPLAY 0.617021 (-6025 2525);
PAINT SKYBLUE (-6025 2525);
FORCEPROP 1 LAST VALUE 0.0
J 2
(-6100 2575);
DISPLAY 0.617021 (-6100 2575);
PAINT SKYBLUE (-6100 2575);
FORCEPROP 1 LAST PART_NUMBER G21497-005
J 0
(-6150 2625);
DISPLAY 0.617021 (-6150 2625);
PAINT BLUE (-6150 2625);
FORCEPROP 1 LAST MATERIAL CHIP
J 0
(-6000 2525);
DISPLAY 0.617021 (-6000 2525);
PAINT SKYBLUE (-6000 2525);
FORCEPROP 1 LASTPIN (-6100 2675) $PN 1
J 0
(-6088 2687);
DISPLAY 0.617021 (-6088 2687);
PAINT ORANGE (-6088 2687);
FORCEPROP 1 LAST LOCATION R4G4
J 0
(-6050 2725);
DISPLAY 0.617021 (-6050 2725);
PAINT AQUA (-6050 2725);
FORCEPROP 1 LAST TOLERANCE 5%
J 0
(-6050 2575);
DISPLAY 0.617021 (-6050 2575);
PAINT SKYBLUE (-6050 2575);
FORCEPROP 1 LASTPIN (-5900 2675) $PN 2
J 0
(-5938 2687);
DISPLAY 0.617021 (-5938 2687);
PAINT ORANGE (-5938 2687);
FORCEPROP 1 LAST PACK_TYPE 0402
J 0
(-5925 2575);
DISPLAY 0.617021 (-5925 2575);
PAINT SKYBLUE (-5925 2575);
FORCEPROP 2 LAST CDS_LOCATION R4G4
J 0
(-6050 2725);
DISPLAY 0.617021 (-6050 2725);
PAINT AQUA (-6050 2725);
DISPLAY INVISIBLE (-6050 2725);
FORCEPROP 2 LAST CDS_LIB mstr_discrete
J 0
(-6000 2675);
PAINT ORANGE (-6000 2675);
DISPLAY INVISIBLE (-6000 2675);
FORCEPROP 2 LAST ROOM PVCCIN_CPU0_VR
J 0
(-6050 2775);
DISPLAY 1.361702 (-6050 2775);
PAINT ORANGE (-6050 2775);
DISPLAY INVISIBLE (-6050 2775);
FORCEPROP 2 LAST SEC_TYPE 0402
J 0
(-6050 2875);
DISPLAY 1.021277 (-6050 2875);
PAINT ORANGE (-6050 2875);
DISPLAY INVISIBLE (-6050 2875);
FORCEPROP 2 LAST SEC 1
J 0
(-6050 2875);
PAINT MONO (-6050 2875);
DISPLAY INVISIBLE (-6050 2875);
FORCEPROP 1 LAST PATH I275
J 0
(-6050 2825);
DISPLAY 0.978723 (-6050 2825);
PAINT WHITE (-6050 2825);
DISPLAY INVISIBLE (-6050 2825);
FORCEADD AGND_SCSI..1
(-1275 1025);
FORCEPROP 3 LASTPIN (-1275 1075) SIG_NAME AGND_PVPP_GHJ\g
J 0
(-1265 1085);
DISPLAY 0.659574 (-1265 1085);
PAINT MONO (-1265 1085);
DISPLAY INVISIBLE (-1265 1085);
FORCEPROP 1 LAST HDL_POWER AGND_PVPP_GHJ
J 1
(-1250 950);
DISPLAY 0.617021 (-1250 950);
PAINT GREEN (-1250 950);
FORCEPROP 1 LAST VOLTAGE 0.0V
J 0
(-1320 982);
DISPLAY 0.340426 (-1320 982);
PAINT SKYBLUE (-1320 982);
DISPLAY INVISIBLE (-1320 982);
FORCEPROP 2 LAST BOM_COST PVPP_KLM_VR
J 0
(-1425 975);
DISPLAY 1.042553 (-1425 975);
PAINT WHITE (-1425 975);
DISPLAY INVISIBLE (-1425 975);
FORCEPROP 1 LAST BODY_TYPE PLUMBING
J 0
(-1320 982);
DISPLAY 0.340426 (-1320 982);
PAINT GREEN (-1320 982);
DISPLAY INVISIBLE (-1320 982);
FORCEPROP 2 LAST ROOM PVPP_KLM_VR
J 0
(-1425 975);
DISPLAY 1.042553 (-1425 975);
PAINT GREEN (-1425 975);
DISPLAY INVISIBLE (-1425 975);
FORCEPROP 2 LAST CDS_LIB mstr_symbols
J 0
(-1275 1025);
PAINT ORANGE (-1275 1025);
DISPLAY INVISIBLE (-1275 1025);
FORCEPROP 1 LAST PATH I276
J 0
(-1200 1025);
DISPLAY 0.872340 (-1200 1025);
PAINT AQUA (-1200 1025);
DISPLAY INVISIBLE (-1200 1025);
FORCEADD INDUCTOR..1
(-2175 3700);
FORCEPROP 1 LAST VALUE 0.47UH
J 2
(-2305 3715);
DISPLAY 0.617021 (-2305 3715);
PAINT SKYBLUE (-2305 3715);
FORCEPROP 1 LASTPIN (-2275 3700) $PN 1
J 0
(-2275 3710);
DISPLAY 0.617021 (-2275 3710);
PAINT WHITE (-2275 3710);
FORCEPROP 1 LAST MATERIAL IND
J 0
(-2210 3640);
DISPLAY 0.617021 (-2210 3640);
PAINT SKYBLUE (-2210 3640);
FORCEPROP 1 LAST LOCATION L4G1
J 0
(-2225 3750);
DISPLAY 0.617021 (-2225 3750);
PAINT AQUA (-2225 3750);
FORCEPROP 1 LASTPIN (-2075 3700) $PN 2
J 2
(-2065 3710);
DISPLAY 0.617021 (-2065 3710);
PAINT WHITE (-2065 3710);
FORCEPROP 1 LAST PART_NUMBER E13358-018
J 0
(-2275 3800);
DISPLAY 0.617021 (-2275 3800);
PAINT BLUE (-2275 3800);
FORCEPROP 1 LAST PACK_TYPE SM
J 0
(-2035 3715);
DISPLAY 0.617021 (-2035 3715);
PAINT SKYBLUE (-2035 3715);
FORCEPROP 2 LAST CDS_LOCATION L4G1
J 0
(-2225 3750);
DISPLAY 0.617021 (-2225 3750);
PAINT AQUA (-2225 3750);
DISPLAY INVISIBLE (-2225 3750);
FORCEPROP 2 LAST ROOM PVPP_GHJ_VR
J 2
(-2175 3700);
PAINT GREEN (-2175 3700);
DISPLAY INVISIBLE (-2175 3700);
FORCEPROP 2 LAST CDS_LIB mstr_discrete
J 0
(-2175 3700);
PAINT ORANGE (-2175 3700);
DISPLAY INVISIBLE (-2175 3700);
FORCEPROP 2 LAST BOM_COST PVPP_GHJ_VR
J 0
(-2175 3700);
PAINT WHITE (-2175 3700);
DISPLAY INVISIBLE (-2175 3700);
FORCEPROP 1 LAST PATH I277
J 0
(-2275 3850);
DISPLAY 0.978723 (-2275 3850);
PAINT ORANGE (-2275 3850);
DISPLAY INVISIBLE (-2275 3850);
FORCEPROP 2 LAST SEC 1
J 0
(-2275 3900);
DISPLAY 0.680851 (-2275 3900);
PAINT MONO (-2275 3900);
DISPLAY INVISIBLE (-2275 3900);
FORCEPROP 2 LAST REUSE_ID 30
J 0
(-2275 3900);
DISPLAY 1.042553 (-2275 3900);
PAINT ORANGE (-2275 3900);
DISPLAY INVISIBLE (-2275 3900);
FORCEPROP 2 LAST SEC_TYPE SM
J 0
(-2275 3900);
DISPLAY 1.021277 (-2275 3900);
PAINT ORANGE (-2275 3900);
DISPLAY INVISIBLE (-2275 3900);
FORCEPROP 0 LAST TOLERANCE 1%
J 0
(-2275 3850);
PAINT SKYBLUE (-2275 3850);
DISPLAY INVISIBLE (-2275 3850);
FORCEADD DNS..2
(-2570 3195);
PAINT RED (-2570 3195);
FORCEPROP 1 LAST COMMENT_BODY TRUE
R 1
J 0
(-2495 2970);
DISPLAY 0.872340 (-2495 2970);
PAINT GREEN (-2495 2970);
DISPLAY INVISIBLE (-2495 2970);
FORCEPROP 2 LAST CDS_LIB mstr_misc
J 0
(-2570 3195);
PAINT ORANGE (-2570 3195);
DISPLAY INVISIBLE (-2570 3195);
FORCEADD DNS..2
(-2570 3545);
PAINT RED (-2570 3545);
FORCEPROP 1 LAST COMMENT_BODY TRUE
R 1
J 0
(-2495 3320);
DISPLAY 0.872340 (-2495 3320);
PAINT GREEN (-2495 3320);
DISPLAY INVISIBLE (-2495 3320);
FORCEPROP 2 LAST CDS_LIB mstr_misc
J 0
(-2570 3545);
PAINT ORANGE (-2570 3545);
DISPLAY INVISIBLE (-2570 3545);
FORCEADD DNS..2
(-6495 2195);
PAINT RED (-6495 2195);
FORCEPROP 1 LAST COMMENT_BODY TRUE
R 1
J 0
(-6420 1970);
DISPLAY 0.872340 (-6420 1970);
PAINT GREEN (-6420 1970);
DISPLAY INVISIBLE (-6420 1970);
FORCEPROP 2 LAST CDS_LIB mstr_misc
J 0
(-6495 2195);
PAINT ORANGE (-6495 2195);
DISPLAY INVISIBLE (-6495 2195);
FORCEADD INTEL_CORP_BPAGE..1
(-375 -75);
FORCEPROP 1 LAST CDS_CON_LAST_MODIFIED Tue Dec 01 11:52:29 2015
J 0
(-1800 250);
DISPLAY 0.489362 (-1800 250);
PAINT GREEN (-1800 250);
DISPLAY INVISIBLE (-1800 250);
FORCEPROP 1 LAST CUSTOM_TXT_CDS <CURRENT_DESIGN_SHEET> OF <TOTAL_DESIGN_SHEETS>
J 0
(-875 -50);
PAINT GREEN (-875 -50);
FORCEPROP 1 LAST CUSTOM_TXT_CDS <CON_LAST_MODIFIED>
J 0
(-2300 275);
PAINT GREEN (-2300 275);
FORCEPROP 2 LAST CUSTOM_TXT_CDS <XR_PAGE_TITLE>
J 0
(-8265 5175);
DISPLAY 0.638298 (-8265 5175);
PAINT PINK (-8265 5175);
DISPLAY INVISIBLE (-8265 5175);
FORCEPROP 1 LAST SCH_ADDRESS3 Santa Clara, CA 95052-8119
J 0
(-4350 -50);
DISPLAY 0.617021 (-4350 -50);
PAINT GREEN (-4350 -50);
FORCEPROP 1 LAST SCH_ADDRESS2 P.O. BOX 58119
J 0
(-4350 0);
DISPLAY 0.617021 (-4350 0);
PAINT GREEN (-4350 0);
FORCEPROP 1 LAST SCH_TITLE VPP GHJ VR
J 0
(-8250 50);
DISPLAY 1.212766 (-8250 50);
PAINT GREEN (-8250 50);
FORCEPROP 1 LAST SCH_ADDRESS1 2200 Mission College Blvd.
J 0
(-4350 50);
DISPLAY 0.617021 (-4350 50);
PAINT GREEN (-4350 50);
FORCEPROP 1 LAST SCH_NUMBER H4694802
J 0
(-1675 75);
DISPLAY 1.212766 (-1675 75);
PAINT YELLOW (-1675 75);
FORCEPROP 1 LAST SCH_DEPT BESD
J 1
(-4825 25);
DISPLAY 1.212766 (-4825 25);
PAINT YELLOW (-4825 25);
FORCEPROP 1 LAST SCH_REV 2.420
J 0
(-625 75);
DISPLAY 0.978723 (-625 75);
PAINT YELLOW (-625 75);
FORCEPROP 2 LAST CDS_LIB mstr_symbols
J 0
(-375 -75);
DISPLAY 0.489362 (-375 -75);
PAINT ORANGE (-375 -75);
DISPLAY INVISIBLE (-375 -75);
FORCEPROP 1 LAST COMMENT_BODY TRUE
J 0
(-363 -63);
DISPLAY 0.234043 (-363 -63);
PAINT GREEN (-363 -63);
DISPLAY INVISIBLE (-363 -63);
FORCEPROP 2 LAST PAGE_BORDER TRUE
J 0
(-8265 5175);
DISPLAY 0.425532 (-8265 5175);
PAINT PINK (-8265 5175);
DISPLAY INVISIBLE (-8265 5175);
FORCEPROP 2 LAST CDS_XR_PAGE_TITLE CR-233 : @BASEBOARD_FAB2_LIB.BASEBOARD_FAB2(SCH_1):PAGE233
J 0
(-8265 5175);
DISPLAY 0.638298 (-8265 5175);
PAINT PINK (-8265 5175);
DISPLAY INVISIBLE (-8265 5175);
WIRE 16 -1 (-5075 825)(-5075 900);
WIRE 16 -1 (-5075 900)(-5325 900);
WIRE 16 -1 (-5325 800)(-5325 900);
WIRE 16 -1 (-5325 900)(-5600 900);
WIRE 16 -1 (-5600 800)(-5600 900);
WIRE 16 -1 (-5600 900)(-5875 900);
WIRE 16 -1 (-5875 825)(-5875 900);
WIRE 16 -1 (-5875 900)(-6175 900);
WIRE 16 -1 (-6175 825)(-6175 900);
WIRE 16 -1 (-6175 900)(-6475 900);
WIRE 16 -1 (-6475 900)(-6475 825);
WIRE 16 -1 (-6475 900)(-6750 900);
WIRE 16 -1 (-6750 825)(-6750 900);
WIRE 16 -1 (-6750 900)(-7050 900);
WIRE 16 -1 (-7050 825)(-7050 900);
WIRE 16 -1 (-7050 900)(-7325 900);
WIRE 16 -1 (-7325 800)(-7325 900);
WIRE 16 -1 (-7325 900)(-7575 900);
WIRE 16 -1 (-7575 825)(-7575 900);
WIRE 16 -1 (-7575 900)(-7850 900);
WIRE 16 -1 (-7850 825)(-7850 900);
WIRE 16 -1 (-8100 900)(-7850 900);
WIRE 16 -1 (-8100 900)(-8100 950);
WIRE 16 -1 (-8100 900)(-8100 825);
WIRE 16 -1 (-8100 625)(-8100 475);
WIRE 16 -1 (-8100 475)(-7850 475);
WIRE 16 -1 (-7850 625)(-7850 475);
WIRE 16 -1 (-7575 475)(-7850 475);
WIRE 16 -1 (-7575 625)(-7575 475);
WIRE 16 -1 (-7325 475)(-7575 475);
WIRE 16 -1 (-7325 600)(-7325 475);
WIRE 16 -1 (-7050 475)(-7325 475);
WIRE 16 -1 (-7050 625)(-7050 475);
WIRE 16 -1 (-6750 475)(-7050 475);
WIRE 16 -1 (-6750 625)(-6750 475);
WIRE 16 -1 (-6475 475)(-6750 475);
WIRE 16 -1 (-6475 625)(-6475 475);
WIRE 16 -1 (-6175 475)(-6475 475);
WIRE 16 -1 (-6175 625)(-6175 475);
WIRE 16 -1 (-5875 475)(-6175 475);
WIRE 16 -1 (-5875 625)(-5875 475);
WIRE 16 -1 (-5600 475)(-5875 475);
WIRE 16 -1 (-5600 600)(-5600 475);
WIRE 16 -1 (-5325 475)(-5600 475);
WIRE 16 -1 (-5325 600)(-5325 475);
WIRE 16 -1 (-5150 475)(-5325 475);
WIRE 16 -1 (-5150 475)(-5075 475);
WIRE 16 -1 (-5150 475)(-5150 450);
WIRE 16 -1 (-5075 625)(-5075 475);
WIRE 16 -1 (-1400 550)(-1200 550);
WIRE 16 -1 (-1400 500)(-1400 550);
WIRE 16 -1 (-850 550)(-1000 550);
WIRE 16 -1 (-850 500)(-850 550);
WIRE 16 -1 (-2000 3625)(-2000 3700);
WIRE 16 -1 (-2000 3700)(-1675 3700);
WIRE 16 -1 (-2075 3700)(-2000 3700);
WIRE 16 -1 (-1675 3700)(-1375 3700);
WIRE 16 -1 (-1675 3700)(-1675 3625);
WIRE 16 -1 (-1375 3600)(-1375 3700);
WIRE 16 -1 (-1375 3700)(-1075 3700);
WIRE 16 -1 (-1075 3700)(-775 3700);
WIRE 16 -1 (-1075 3700)(-1075 3625);
WIRE 16 -1 (-725 3700)(-775 3700);
WIRE 16 -1 (-775 3700)(-775 3600);
WIRE 16 -1 (-525 3700)(-725 3700);
WIRE 16 -1 (-725 3775)(-725 3700);
WIRE 16 -1 (-525 3700)(-525 3025);
WIRE 16 -1 (-1275 3025)(-525 3025);
WIRE 16 -1 (-1275 3025)(-1275 2875);
WIRE 16 -1 (-7175 1775)(-7175 2025);
WIRE 16 -1 (-4150 1325)(-4150 1200);
WIRE 16 -1 (-7025 3850)(-7025 3900);
WIRE 16 -1 (-4875 3725)(-4875 3900);
WIRE 16 -1 (-7400 4150)(-7325 4150);
WIRE 16 -1 (-7400 4300)(-7400 4150);
WIRE 16 -1 (-3800 475)(-3800 375);
WIRE 16 -1 (-3225 2575)(-3000 2575);
WIRE 16 -1 (-3000 2575)(-3000 2525);
WIRE 16 -1 (-3225 2525)(-3000 2525);
WIRE 16 -1 (-3000 2525)(-3000 2475);
WIRE 16 -1 (-3225 2475)(-3000 2475);
WIRE 16 -1 (-3000 2475)(-3000 2425);
WIRE 16 -1 (-3225 2425)(-3000 2425);
WIRE 16 -1 (-3000 2425)(-3000 2375);
WIRE 16 -1 (-3225 2375)(-3000 2375);
WIRE 16 -1 (-3000 2375)(-3000 2325);
WIRE 16 -1 (-3225 2325)(-3000 2325);
WIRE 16 -1 (-3000 2325)(-3000 2275);
WIRE 16 -1 (-3225 2275)(-3000 2275);
WIRE 16 -1 (-3000 2275)(-3000 2225);
WIRE 16 -1 (-3225 2225)(-3000 2225);
WIRE 16 -1 (-3000 2225)(-3000 2175);
WIRE 16 -1 (-3225 2175)(-3000 2175);
WIRE 16 -1 (-3000 2175)(-3000 2125);
WIRE 16 -1 (-3225 2125)(-3000 2125);
WIRE 16 -1 (-3000 2125)(-3000 2075);
WIRE 16 -1 (-3225 2075)(-3000 2075);
WIRE 16 -1 (-3000 2075)(-3000 2025);
WIRE 16 -1 (-3225 2025)(-3000 2025);
WIRE 16 -1 (-3000 2025)(-3000 1975);
WIRE 16 -1 (-3225 1975)(-3000 1975);
WIRE 16 -1 (-3000 1975)(-3000 1925);
WIRE 16 -1 (-3225 1925)(-3000 1925);
WIRE 16 -1 (-3000 1925)(-3000 1875);
WIRE 16 -1 (-3225 1875)(-3000 1875);
WIRE 16 -1 (-3000 1875)(-3000 1825);
WIRE 16 -1 (-2575 3100)(-2575 3050);
WIRE 16 -1 (-2000 3325)(-2000 3425);
WIRE 16 -1 (-1675 3350)(-1675 3425);
WIRE 16 -1 (-1075 3375)(-1075 3425);
WIRE 16 -1 (-6500 1850)(-6500 2100);
WIRE 16 -1 (-5525 2000)(-5525 2150);
WIRE 16 -1 (-5000 1925)(-5000 1850);
WIRE 16 -1 (-4675 1400)(-4675 1250);
WIRE 16 -1 (-4300 1875)(-4225 1875);
WIRE 16 -1 (-4300 1750)(-4300 1875);
WIRE 16 -1 (-5050 3225)(-5050 3150);
WIRE 16 -1 (-5300 2775)(-4225 2775);
WIRE 16 -1 (-5300 2625)(-5300 2775);
WIRE 16 -1 (-1375 3375)(-1375 3400);
WIRE 16 -1 (-6700 3825)(-6700 3875);
WIRE 16 -1 (-6300 3825)(-6300 3875);
WIRE 16 -1 (-5875 3825)(-5875 3875);
WIRE 16 -1 (-5450 3825)(-5450 3875);
WIRE 16 -1 (-1275 1075)(-1275 1300);
WIRE 16 -1 (-6500 2300)(-6500 2675);
WIRE 16 -1 (-6500 2675)(-6100 2675);
WIRE 16 -1 (-7175 2675)(-6500 2675);
WIRE 16 -1 (-7525 2675)(-7175 2675);
FORCEPROP 2 LAST SIG_NAME FM_PVPP_CPU1_EN
J 0
(-7501 2700);
DISPLAY 0.617021 (-7501 2700);
PAINT ORANGE (-7501 2700);
WIRE 16 -1 (-7175 2225)(-7175 2675);
WIRE 16 682 (-875 4600)(-1925 4600);
WIRE 16 682 (-875 4050)(-875 4600);
WIRE 16 682 (-1925 4600)(-1925 4050);
WIRE 16 682 (-1925 4050)(-875 4050);
WIRE 16 2175 (-3100 4225)(-3100 3850);
WIRE 16 2175 (-4325 4225)(-3100 4225);
WIRE 16 2175 (-3100 3850)(-4325 3850);
WIRE 16 2175 (-4325 3850)(-4325 4225);
WIRE 16 -1 (-950 2575)(-950 2650);
WIRE 16 -1 (-950 2650)(-1275 2650);
WIRE 16 -1 (-1275 2650)(-1275 2675);
WIRE 16 -1 (-1275 2125)(-1275 2650);
FORCEPROP 0 LAST SIG_NAME VSENSE_PVPP_GHJ
R 1
J 0
(-1285 2160);
DISPLAY 0.617021 (-1285 2160);
PAINT ORANGE (-1285 2160);
FORCEPROP 2 LASTPROP $XRERR UNIQUE?
J 0
(-1525 2160);
DISPLAY 0.638298 (-1525 2160);
PAINT MONO (-1525 2160);
DISPLAY INVISIBLE (-1525 2160);
WIRE 16 2175 (-1350 2975)(-700 2975);
WIRE 16 2175 (-1350 1175)(-1350 2975);
WIRE 16 2175 (-700 2975)(-700 1175);
WIRE 16 2175 (-1350 1175)(-700 1175);
WIRE 16 -1 (-1900 2300)(-1900 2675);
WIRE 16 -1 (-1900 2300)(-1975 2300);
WIRE 16 -1 (-1900 2675)(-1900 2775);
WIRE 16 -1 (-2250 2675)(-1900 2675);
WIRE 16 -1 (-1800 2775)(-1900 2775);
WIRE 16 -1 (-3225 2775)(-1900 2775);
WIRE 16 -1 (-1800 1575)(-1800 2775);
WIRE 16 -1 (-1800 1575)(-1275 1575);
FORCEPROP 0 LAST SIG_NAME VR_FB_PVPP_GHJ
J 0
(-1760 1585);
DISPLAY 0.617021 (-1760 1585);
PAINT ORANGE (-1760 1585);
FORCEPROP 2 LASTPROP $XRERR UNIQUE?
J 0
(-2000 1585);
DISPLAY 0.638298 (-2000 1585);
PAINT MONO (-2000 1585);
DISPLAY INVISIBLE (-2000 1585);
WIRE 16 -1 (-1275 1675)(-1275 1575);
WIRE 16 -1 (-1275 1575)(-1275 1500);
WIRE 16 -1 (-950 1675)(-1275 1675);
WIRE 16 -1 (-1275 1925)(-1275 1675);
WIRE 16 -1 (-950 1825)(-950 1675);
WIRE 16 -1 (-950 2025)(-950 2375);
FORCEPROP 0 LAST SIG_NAME VR_COMP_PVPP_GHJ
R 1
J 0
(-960 2010);
DISPLAY 0.617021 (-960 2010);
PAINT ORANGE (-960 2010);
FORCEPROP 2 LASTPROP $XRERR UNIQUE?
J 0
(-1200 2010);
DISPLAY 0.638298 (-1200 2010);
PAINT MONO (-1200 2010);
DISPLAY INVISIBLE (-1200 2010);
WIRE 16 -1 (-2575 3650)(-2575 3700);
WIRE 16 -1 (-2275 3700)(-2575 3700);
WIRE 16 -1 (-2950 3700)(-2575 3700);
FORCEPROP 2 LAST SIG_NAME VR_PVPP_GHJ_PHASE
J 0
(-2935 3710);
DISPLAY 0.617021 (-2935 3710);
PAINT ORANGE (-2935 3710);
FORCEPROP 2 LASTPROP $XRERR UNIQUE?
J 0
(-3175 3710);
DISPLAY 0.638298 (-3175 3710);
PAINT MONO (-3175 3710);
DISPLAY INVISIBLE (-3175 3710);
WIRE 16 -1 (-2950 4050)(-2950 3700);
WIRE 16 -1 (-2950 3325)(-2950 3700);
WIRE 16 -1 (-2950 3275)(-2950 3325);
WIRE 16 -1 (-3225 3325)(-2950 3325);
WIRE 16 -1 (-3200 4050)(-2950 4050);
WIRE 16 -1 (-2950 3225)(-2950 3275);
WIRE 16 -1 (-3225 3275)(-2950 3275);
WIRE 16 -1 (-2950 3175)(-2950 3225);
WIRE 16 -1 (-3225 3225)(-2950 3225);
WIRE 16 -1 (-2950 3125)(-2950 3175);
WIRE 16 -1 (-3225 3175)(-2950 3175);
WIRE 16 -1 (-2950 3075)(-2950 3125);
WIRE 16 -1 (-3225 3125)(-2950 3125);
WIRE 16 -1 (-2950 3025)(-2950 3075);
WIRE 16 -1 (-3225 3075)(-2950 3075);
WIRE 16 -1 (-2950 2975)(-2950 3025);
WIRE 16 -1 (-3225 3025)(-2950 3025);
WIRE 16 -1 (-2950 2875)(-2950 2975);
WIRE 16 -1 (-3225 2975)(-2950 2975);
WIRE 16 -1 (-3225 2875)(-2950 2875);
WIRE 16 -1 (-2575 3300)(-2575 3450);
FORCEPROP 2 LAST SIG_NAME VR_PVPP_GHJ_SNUB
J 0
(-2560 3360);
DISPLAY 0.617021 (-2560 3360);
PAINT ORANGE (-2560 3360);
FORCEPROP 2 LASTPROP $XRERR UNIQUE?
J 0
(-2800 3360);
DISPLAY 0.638298 (-2800 3360);
PAINT MONO (-2800 3360);
DISPLAY INVISIBLE (-2800 3360);
WIRE 16 -1 (-2925 2675)(-2450 2675);
WIRE 16 -1 (-2925 2300)(-2925 2675);
FORCEPROP 0 LAST SIG_NAME VR_COMP_PVPP_GHJ_3
J 0
(-2960 2685);
DISPLAY 0.617021 (-2960 2685);
PAINT ORANGE (-2960 2685);
FORCEPROP 2 LASTPROP $XRERR UNIQUE?
J 0
(-3200 2685);
DISPLAY 0.638298 (-3200 2685);
PAINT MONO (-3200 2685);
DISPLAY INVISIBLE (-3200 2685);
WIRE 16 -1 (-3225 2675)(-2925 2675);
WIRE 16 -1 (-2875 2300)(-2925 2300);
WIRE 16 -1 (-2175 2300)(-2675 2300);
FORCEPROP 0 LAST SIG_NAME VR_COMP_RC_PVPP_GHJ
J 0
(-2660 2310);
DISPLAY 0.617021 (-2660 2310);
PAINT ORANGE (-2660 2310);
FORCEPROP 2 LASTPROP $XRERR UNIQUE?
J 0
(-2900 2310);
DISPLAY 0.638298 (-2900 2310);
PAINT MONO (-2900 2310);
DISPLAY INVISIBLE (-2900 2310);
WIRE 16 -1 (-3175 3750)(-3175 3425);
WIRE 16 -1 (-4225 3750)(-3175 3750);
WIRE 16 -1 (-3175 3425)(-3225 3425);
WIRE 16 -1 (-4225 4050)(-4225 3750);
FORCEPROP 2 LAST SIG_NAME VR_PVPP_GHJ_BOOT
J 0
(-4135 3785);
DISPLAY 0.617021 (-4135 3785);
PAINT ORANGE (-4135 3785);
FORCEPROP 2 LASTPROP $XRERR UNIQUE?
J 0
(-4375 3785);
DISPLAY 0.638298 (-4375 3785);
PAINT MONO (-4375 3785);
DISPLAY INVISIBLE (-4375 3785);
WIRE 16 -1 (-4100 4050)(-4225 4050);
WIRE 16 -1 (-3400 4050)(-3900 4050);
FORCEPROP 2 LAST SIG_NAME VR_PVPP_GHJ_BOOT_R
J 0
(-3880 4060);
DISPLAY 0.617021 (-3880 4060);
PAINT ORANGE (-3880 4060);
FORCEPROP 2 LASTPROP $XRERR UNIQUE?
J 0
(-4120 4060);
DISPLAY 0.638298 (-4120 4060);
PAINT MONO (-4120 4060);
DISPLAY INVISIBLE (-4120 4060);
WIRE 16 -1 (-2600 825)(-3275 825);
FORCEPROP 2 LAST SIG_NAME PWRGD_PVPP_GHJ
J 0
(-2985 835);
DISPLAY 0.617021 (-2985 835);
PAINT ORANGE (-2985 835);
WIRE 16 -1 (-3800 675)(-3800 825);
WIRE 16 -1 (-3475 825)(-3800 825);
FORCEPROP 2 LAST SIG_NAME PWRGD_PVPP_GHJ_R
J 0
(-4035 835);
DISPLAY 0.617021 (-4035 835);
PAINT ORANGE (-4035 835);
FORCEPROP 2 LASTPROP $XRERR UNIQUE?
J 0
(-4275 835);
DISPLAY 0.638298 (-4275 835);
PAINT MONO (-4275 835);
DISPLAY INVISIBLE (-4275 835);
WIRE 16 -1 (-3800 825)(-4150 825);
WIRE 16 -1 (-4150 1000)(-4150 825);
WIRE 16 -1 (-4150 825)(-4475 825);
WIRE 16 -1 (-4475 825)(-4475 2375);
WIRE 16 -1 (-4225 2375)(-4475 2375);
WIRE 16 -1 (-7125 4150)(-7025 4150);
WIRE 16 -1 (-7025 4150)(-6700 4150);
WIRE 16 -1 (-7025 4100)(-7025 4150);
WIRE 16 -1 (-6700 4150)(-6300 4150);
WIRE 16 -1 (-6700 4075)(-6700 4150);
WIRE 16 -1 (-5875 4150)(-6300 4150);
WIRE 16 -1 (-6300 4075)(-6300 4150);
WIRE 16 -1 (-5450 4150)(-5875 4150);
FORCEPROP 0 LAST SIG_NAME VR_FET_SW_P12V_STBY_PVPP_GHJ
J 0
(-5835 4160);
DISPLAY 0.617021 (-5835 4160);
PAINT ORANGE (-5835 4160);
FORCEPROP 2 LASTPROP $XRERR UNIQUE?
J 0
(-6075 4160);
DISPLAY 0.638298 (-6075 4160);
PAINT MONO (-6075 4160);
DISPLAY INVISIBLE (-6075 4160);
WIRE 16 -1 (-5875 4075)(-5875 4150);
WIRE 16 -1 (-5450 4150)(-4875 4150);
WIRE 16 -1 (-5450 4075)(-5450 4150);
WIRE 16 -1 (-4875 4150)(-4650 4150);
WIRE 16 -1 (-4875 4100)(-4875 4150);
WIRE 16 -1 (-4650 4150)(-4650 3525);
WIRE 16 -1 (-4650 3525)(-4650 3425);
WIRE 16 -1 (-5050 3525)(-4650 3525);
WIRE 16 -1 (-5050 3425)(-5050 3525);
WIRE 16 -1 (-4225 3425)(-4650 3425);
WIRE 16 -1 (-4650 3425)(-4650 3325);
WIRE 16 -1 (-4650 3325)(-4225 3325);
WIRE 16 -1 (-4650 3275)(-4650 3325);
WIRE 16 -1 (-4225 3275)(-4650 3275);
WIRE 16 -1 (-4650 3225)(-4650 3275);
WIRE 16 -1 (-4225 3225)(-4650 3225);
WIRE 16 -1 (-4650 3175)(-4650 3225);
WIRE 16 -1 (-4225 3175)(-4650 3175);
WIRE 16 -1 (-4650 3125)(-4650 3175);
WIRE 16 -1 (-4225 3125)(-4650 3125);
WIRE 16 -1 (-4650 3075)(-4650 3125);
WIRE 16 -1 (-4225 3075)(-4650 3075);
WIRE 16 -1 (-4650 3025)(-4650 3075);
WIRE 16 -1 (-4225 3025)(-4650 3025);
WIRE 16 -1 (-4650 2975)(-4650 3025);
WIRE 16 -1 (-4225 2975)(-4650 2975);
WIRE 16 2175 (-7075 4250)(-5125 4250);
WIRE 16 2175 (-7075 3725)(-7075 4250);
WIRE 16 2175 (-5125 4250)(-5125 3725);
WIRE 16 2175 (-5125 3725)(-7075 3725);
WIRE 16 -1 (-4675 2475)(-4225 2475);
WIRE 16 -1 (-4675 1600)(-4675 2475);
FORCEPROP 2 LAST SIG_NAME VR_PVPP_GHJ_ISET
R 1
J 0
(-4685 1960);
DISPLAY 0.617021 (-4685 1960);
PAINT ORANGE (-4685 1960);
FORCEPROP 2 LASTPROP $XRERR UNIQUE?
J 0
(-4925 1960);
DISPLAY 0.638298 (-4925 1960);
PAINT MONO (-4925 1960);
DISPLAY INVISIBLE (-4925 1960);
WIRE 16 -1 (-4225 2575)(-5000 2575);
WIRE 16 -1 (-5000 2575)(-5000 2125);
FORCEPROP 2 LAST SIG_NAME VR_PVPP_GHJ_SS
R 1
J 0
(-5010 2135);
DISPLAY 0.617021 (-5010 2135);
PAINT ORANGE (-5010 2135);
FORCEPROP 2 LASTPROP $XRERR UNIQUE?
J 0
(-5250 2135);
DISPLAY 0.638298 (-5250 2135);
PAINT MONO (-5250 2135);
DISPLAY INVISIBLE (-5250 2135);
WIRE 16 -1 (-5525 2875)(-4225 2875);
FORCEPROP 0 LAST SIG_NAME VR_VB_PVPP_GHJ
J 0
(-5235 2885);
DISPLAY 0.617021 (-5235 2885);
PAINT ORANGE (-5235 2885);
FORCEPROP 2 LASTPROP $XRERR UNIQUE?
J 0
(-5475 2885);
DISPLAY 0.638298 (-5475 2885);
PAINT MONO (-5475 2885);
DISPLAY INVISIBLE (-5475 2885);
WIRE 16 -1 (-5525 2350)(-5525 2875);
WIRE 16 -1 (-5900 2675)(-4225 2675);
FORCEPROP 2 LAST SIG_NAME FM_PVPP_PVDDQ_CPU1_EN_GHJ
J 0
(-5476 2700);
DISPLAY 0.617021 (-5476 2700);
PAINT ORANGE (-5476 2700);
FORCEPROP 2 LASTPROP $XRERR UNIQUE?
J 0
(-5716 2700);
DISPLAY 0.638298 (-5716 2700);
PAINT MONO (-5716 2700);
DISPLAY INVISIBLE (-5716 2700);
WIRE 16 2175 (-4825 1150)(-4825 350);
WIRE 16 2175 (-8225 1150)(-4825 1150);
WIRE 16 2175 (-4825 350)(-8225 350);
WIRE 16 2175 (-8225 350)(-8225 1150);
DOT 1 (-7850 475);
DOT 1 (-8100 900);
DOT 1 (-7850 900);
DOT 1 (-7325 475);
DOT 1 (-7575 475);
DOT 1 (-7575 900);
DOT 1 (-7325 900);
DOT 1 (-7050 475);
DOT 1 (-6750 475);
DOT 1 (-7050 900);
DOT 1 (-6750 900);
DOT 1 (-6175 475);
DOT 1 (-6475 475);
DOT 1 (-6475 900);
DOT 1 (-6175 900);
DOT 1 (-7175 2675);
DOT 1 (-6500 2675);
DOT 1 (-5875 475);
DOT 1 (-5875 900);
DOT 1 (-5600 475);
DOT 1 (-5325 475);
DOT 1 (-5150 475);
DOT 1 (-5600 900);
DOT 1 (-5325 900);
DOT 1 (-4150 825);
DOT 1 (-4650 3025);
DOT 1 (-4650 3075);
DOT 1 (-4650 3125);
DOT 1 (-4650 3175);
DOT 1 (-4650 3225);
DOT 1 (-4650 3275);
DOT 1 (-4650 3325);
DOT 1 (-4650 3425);
DOT 1 (-4650 3525);
DOT 1 (-7025 4150);
DOT 1 (-6700 4150);
DOT 1 (-6300 4150);
DOT 1 (-5875 4150);
DOT 1 (-5450 4150);
DOT 1 (-4875 4150);
DOT 1 (-3800 825);
DOT 1 (-3000 1875);
DOT 1 (-3000 1925);
DOT 1 (-3000 2025);
DOT 1 (-3000 1975);
DOT 1 (-3000 2175);
DOT 1 (-3000 2075);
DOT 1 (-3000 2125);
DOT 1 (-3000 2275);
DOT 1 (-3000 2225);
DOT 1 (-3000 2425);
DOT 1 (-3000 2325);
DOT 1 (-3000 2375);
DOT 1 (-3000 2475);
DOT 1 (-3000 2525);
DOT 1 (-2925 2675);
DOT 1 (-2950 3025);
DOT 1 (-2950 2975);
DOT 1 (-2950 3075);
DOT 1 (-2950 3175);
DOT 1 (-2950 3125);
DOT 1 (-2950 3275);
DOT 1 (-2950 3325);
DOT 1 (-2950 3225);
DOT 1 (-2950 3700);
DOT 1 (-2575 3700);
DOT 1 (-1275 1575);
DOT 1 (-1275 1675);
DOT 1 (-1900 2675);
DOT 1 (-1900 2775);
DOT 1 (-1275 2650);
DOT 1 (-2000 3700);
DOT 1 (-1675 3700);
DOT 1 (-1375 3700);
DOT 1 (-1075 3700);
DOT 1 (-775 3700);
DOT 1 (-725 3700);
FORCENOTE
BOM_COST: PVPP_GHJ_VR
(-7450 0) 0;
DISPLAY LEFT (-7450 0);
DISPLAY 0.787234 (-7450 0);
PAINT PURPLE (-7450 0);
FORCENOTE
ROOM = PVPP_GHJ_VR
(-7450 50) 0;
DISPLAY LEFT (-7450 50);
DISPLAY 0.787234 (-7450 50);
PAINT PURPLE (-7450 50);
FORCENOTE
CAPS TO BE PLACED BETWEEN DIMMS
(-7745 1055) 0;
DISPLAY LEFT (-7745 1055);
DISPLAY 1.021277 (-7745 1055);
PAINT PURPLE (-7745 1055);
FORCENOTE
(0.4V/MS)
(-5270 1955) 0;
DISPLAY LEFT (-5270 1955);
PAINT PURPLE (-5270 1955);
FORCENOTE
25A OC
(-5095 1505) 0;
DISPLAY LEFT (-5095 1505);
PAINT PURPLE (-5095 1505);
FORCENOTE
6.25MS
(-5245 2030) 0;
DISPLAY LEFT (-5245 2030);
PAINT PURPLE (-5245 2030);
FORCENOTE
SPOF
(-4325 4275) 0;
DISPLAY LEFT (-4325 4275);
DISPLAY 1.659574 (-4325 4275);
PAINT PURPLE (-4325 4275);
FORCENOTE
COMPENSATION TYPE III
(-2900 2000) 0;
DISPLAY LEFT (-2900 2000);
DISPLAY 1.042553 (-2900 2000);
PAINT PURPLE (-2900 2000);
FORCENOTE
CONNECT AT SINGLE
(-1400 750) 0;
DISPLAY LEFT (-1400 750);
DISPLAY 1.042553 (-1400 750);
PAINT PURPLE (-1400 750);
FORCENOTE
POINT ONLY TOP TO L2
(-1450 700) 0;
DISPLAY LEFT (-1450 700);
DISPLAY 1.042553 (-1450 700);
PAINT PURPLE (-1450 700);
FORCENOTE
SPOF
(-1130 2825) 0;
DISPLAY LEFT (-1130 2825);
DISPLAY 2.340426 (-1130 2825);
PAINT PURPLE (-1130 2825);
FORCENOTE
PLACE ON
(-4025 4275) 0;
DISPLAY LEFT (-4025 4275);
DISPLAY 1.042553 (-4025 4275);
PAINT PURPLE (-4025 4275);
FORCENOTE
TOP LAYER
(-3650 4275) 0;
DISPLAY LEFT (-3650 4275);
DISPLAY 1.042553 (-3650 4275);
PAINT PURPLE (-3650 4275);
FORCENOTE
IOUT DI/DT = 25A/US
(-1900 4175) 0;
DISPLAY LEFT (-1900 4175);
DISPLAY 1.021277 (-1900 4175);
PAINT PURPLE (-1900 4175);
FORCENOTE
IOUT STEP = 3A
(-1900 4225) 0;
DISPLAY LEFT (-1900 4225);
DISPLAY 1.021277 (-1900 4225);
PAINT PURPLE (-1900 4225);
FORCENOTE
RIPPLE GUIDELINE = +/- 1.0%
(-1900 4475) 0;
DISPLAY LEFT (-1900 4475);
DISPLAY 1.021277 (-1900 4475);
PAINT PURPLE (-1900 4475);
FORCENOTE
DC TOL = +/-1.5%
(-1900 4425) 0;
DISPLAY LEFT (-1900 4425);
DISPLAY 1.021277 (-1900 4425);
PAINT PURPLE (-1900 4425);
FORCENOTE
IOUT TDC = 8A
(-1900 4325) 0;
DISPLAY LEFT (-1900 4325);
DISPLAY 1.021277 (-1900 4325);
PAINT PURPLE (-1900 4325);
FORCENOTE
IOUT PK = 15A
(-1900 4275) 0;
DISPLAY LEFT (-1900 4275);
DISPLAY 1.021277 (-1900 4275);
PAINT PURPLE (-1900 4275);
FORCENOTE
VOUT = 2.5V
(-1900 4525) 0;
DISPLAY LEFT (-1900 4525);
DISPLAY 1.021277 (-1900 4525);
PAINT PURPLE (-1900 4525);
FORCENOTE
AC & RIPPLE TOL = +3.5%, -7.3%
(-1900 4375) 0;
DISPLAY LEFT (-1900 4375);
DISPLAY 1.021277 (-1900 4375);
PAINT PURPLE (-1900 4375);
FORCENOTE
SW FREQ =  500KHZ
(-1900 4125) 0;
DISPLAY LEFT (-1900 4125);
DISPLAY 1.021277 (-1900 4125);
PAINT PURPLE (-1900 4125);
QUIT
